(kicad_sch
	(version 20250114)
	(generator "eeschema")
	(generator_version "9.0")
	(paper "A3")
	(title_block
		(title "CM4 Baseboard")
		(date "2026-01-05")
		(rev "1.1.1")
		(company "Antmicro Ltd")
		(comment 1 "www.antmicro.com")
	)
	(rectangle
		(start 322.58 30.48)
		(end 394.97 39.37)
		(stroke
			(width 0)
			(type default)
		)
		(fill
			(type none)
		)
	)
	(text "I2C_SDA_OUT"
		(exclude_from_sim no)
		(at 378.46 73.66 0)
		(effects
			(font
				(size 1.27 1.27)
			)
			(justify left bottom)
		)
	)
	(text "ISET = 1.5A"
		(exclude_from_sim no)
		(at 137.16 207.01 0)
		(effects
			(font
				(size 1.27 1.27)
			)
			(justify left bottom)
		)
	)
	(text "Note:\nPower path of this baseboard is rated up to 16V.\nConfigure FT4233, so that it would allow power profiles up to 15V@3A"
		(exclude_from_sim no)
		(at 323.85 38.1 0)
		(effects
			(font
				(size 1.27 1.27)
				(thickness 0.254)
				(bold yes)
			)
			(justify left bottom)
		)
	)
	(text "USB Debug"
		(exclude_from_sim no)
		(at 13.97 48.26 0)
		(effects
			(font
				(size 2.54 2.54)
				(bold yes)
			)
			(justify left bottom)
		)
	)
	(text "ESD/EMI protection"
		(exclude_from_sim no)
		(at 53.34 22.86 0)
		(effects
			(font
				(size 2.54 2.54)
				(bold yes)
			)
			(justify left bottom)
		)
	)
	(text "FT4233 EEPROM"
		(exclude_from_sim no)
		(at 161.671 122.809 0)
		(effects
			(font
				(size 2.54 2.54)
				(thickness 0.508)
				(bold yes)
			)
			(justify left bottom)
		)
	)
	(text "USB-C VBUS\nvoltage divider"
		(exclude_from_sim no)
		(at 62.865 120.65 0)
		(effects
			(font
				(size 2.54 2.54)
				(thickness 0.508)
				(bold yes)
			)
			(justify left bottom)
		)
	)
	(text "3V3"
		(exclude_from_sim no)
		(at 238.125 52.705 0)
		(effects
			(font
				(size 1.27 1.27)
			)
			(justify left bottom)
		)
	)
	(text "Decoupling and Filtering"
		(exclude_from_sim no)
		(at 259.08 20.32 0)
		(effects
			(font
				(size 2.54 2.54)
				(thickness 0.508)
				(bold yes)
			)
			(justify left bottom)
		)
	)
	(text "USB source\nswitch"
		(exclude_from_sim no)
		(at 130.81 181.61 0)
		(effects
			(font
				(size 2.54 2.54)
				(thickness 0.508)
				(bold yes)
			)
			(justify left bottom)
		)
	)
	(text "I2C_SCL"
		(exclude_from_sim no)
		(at 378.46 71.12 0)
		(effects
			(font
				(size 1.27 1.27)
			)
			(justify left bottom)
		)
	)
	(text "I2C_SDA_IN"
		(exclude_from_sim no)
		(at 378.46 76.2 0)
		(effects
			(font
				(size 1.27 1.27)
			)
			(justify left bottom)
		)
	)
	(text "USB CC\ncontroller"
		(exclude_from_sim no)
		(at 137.16 241.3 0)
		(effects
			(font
				(size 2.54 2.54)
				(thickness 0.508)
				(bold yes)
			)
			(justify left bottom)
		)
	)
	(text "UART.1.RX"
		(exclude_from_sim no)
		(at 391.795 71.12 0)
		(effects
			(font
				(size 1.27 1.27)
			)
			(justify left bottom)
		)
	)
	(text "ESD/EMI protection"
		(exclude_from_sim no)
		(at 53.34 186.69 0)
		(effects
			(font
				(size 2.54 2.54)
				(bold yes)
			)
			(justify left bottom)
		)
	)
	(text "USB-PD sink\nswitch"
		(exclude_from_sim no)
		(at 115.57 48.26 0)
		(effects
			(font
				(size 2.54 2.54)
				(thickness 0.508)
				(bold yes)
			)
			(justify left bottom)
		)
	)
	(text "USB Application"
		(exclude_from_sim no)
		(at 13.97 186.69 0)
		(effects
			(font
				(size 2.54 2.54)
				(bold yes)
			)
			(justify left bottom)
		)
	)
	(text "UART.1.TX"
		(exclude_from_sim no)
		(at 391.795 73.66 0)
		(effects
			(font
				(size 1.27 1.27)
			)
			(justify left bottom)
		)
	)
	(text "USB source\nCap. with soft-start"
		(exclude_from_sim no)
		(at 200.66 166.37 0)
		(effects
			(font
				(size 2.54 2.54)
				(thickness 0.508)
				(bold yes)
			)
			(justify left bottom)
		)
	)
	(text "USB <-> 4x UART\n& PD controller"
		(exclude_from_sim no)
		(at 336.55 27.94 0)
		(effects
			(font
				(size 2.54 2.54)
				(bold yes)
			)
			(justify left bottom)
		)
	)
	(junction
		(at 191.77 138.43)
		(diameter 0)
		(color 0 0 0 0)
	)
	(junction
		(at 295.91 36.83)
		(diameter 0)
		(color 0 0 0 0)
	)
	(junction
		(at 77.47 58.42)
		(diameter 0)
		(color 0 0 0 0)
	)
	(junction
		(at 289.56 36.83)
		(diameter 0)
		(color 0 0 0 0)
	)
	(junction
		(at 313.69 240.03)
		(diameter 0)
		(color 0 0 0 0)
	)
	(junction
		(at 281.94 36.83)
		(diameter 0)
		(color 0 0 0 0)
	)
	(junction
		(at 50.8 196.85)
		(diameter 0)
		(color 0 0 0 0)
	)
	(junction
		(at 317.5 104.14)
		(diameter 0)
		(color 0 0 0 0)
	)
	(junction
		(at 243.84 54.61)
		(diameter 0)
		(color 0 0 0 0)
	)
	(junction
		(at 281.94 54.61)
		(diameter 0)
		(color 0 0 0 0)
	)
	(junction
		(at 383.54 185.42)
		(diameter 0)
		(color 0 0 0 0)
	)
	(junction
		(at 231.14 54.61)
		(diameter 0)
		(color 0 0 0 0)
	)
	(junction
		(at 322.58 104.14)
		(diameter 0)
		(color 0 0 0 0)
	)
	(junction
		(at 285.75 146.05)
		(diameter 0)
		(color 0 0 0 0)
	)
	(junction
		(at 289.56 69.85)
		(diameter 0)
		(color 0 0 0 0)
	)
	(junction
		(at 325.12 231.14)
		(diameter 0)
		(color 0 0 0 0)
	)
	(junction
		(at 299.72 69.85)
		(diameter 0)
		(color 0 0 0 0)
	)
	(junction
		(at 177.8 140.97)
		(diameter 0)
		(color 0 0 0 0)
	)
	(junction
		(at 153.67 54.61)
		(diameter 0)
		(color 0 0 0 0)
	)
	(junction
		(at 172.72 260.35)
		(diameter 0)
		(color 0 0 0 0)
	)
	(junction
		(at 110.49 196.85)
		(diameter 0)
		(color 0 0 0 0)
	)
	(junction
		(at 147.32 133.35)
		(diameter 0)
		(color 0 0 0 0)
	)
	(junction
		(at 297.18 36.83)
		(diameter 0)
		(color 0 0 0 0)
	)
	(junction
		(at 167.64 201.93)
		(diameter 0)
		(color 0 0 0 0)
	)
	(junction
		(at 40.64 210.82)
		(diameter 0)
		(color 0 0 0 0)
	)
	(junction
		(at 95.25 58.42)
		(diameter 0)
		(color 0 0 0 0)
	)
	(junction
		(at 157.48 184.15)
		(diameter 0)
		(color 0 0 0 0)
	)
	(junction
		(at 281.94 22.86)
		(diameter 0)
		(color 0 0 0 0)
	)
	(junction
		(at 293.37 146.05)
		(diameter 0)
		(color 0 0 0 0)
	)
	(junction
		(at 92.71 196.85)
		(diameter 0)
		(color 0 0 0 0)
	)
	(junction
		(at 92.71 80.01)
		(diameter 0)
		(color 0 0 0 0)
	)
	(junction
		(at 77.47 137.16)
		(diameter 0)
		(color 0 0 0 0)
	)
	(junction
		(at 231.14 194.31)
		(diameter 0)
		(color 0 0 0 0)
	)
	(junction
		(at 198.12 184.15)
		(diameter 0)
		(color 0 0 0 0)
	)
	(junction
		(at 80.01 196.85)
		(diameter 0)
		(color 0 0 0 0)
	)
	(junction
		(at 234.95 54.61)
		(diameter 0)
		(color 0 0 0 0)
	)
	(junction
		(at 40.64 72.39)
		(diameter 0)
		(color 0 0 0 0)
	)
	(junction
		(at 243.84 184.15)
		(diameter 0)
		(color 0 0 0 0)
	)
	(junction
		(at 317.5 132.08)
		(diameter 0)
		(color 0 0 0 0)
	)
	(junction
		(at 179.07 260.35)
		(diameter 0)
		(color 0 0 0 0)
	)
	(junction
		(at 300.99 146.05)
		(diameter 0)
		(color 0 0 0 0)
	)
	(junction
		(at 187.96 135.89)
		(diameter 0)
		(color 0 0 0 0)
	)
	(junction
		(at 328.93 180.34)
		(diameter 0)
		(color 0 0 0 0)
	)
	(junction
		(at 39.37 232.41)
		(diameter 0)
		(color 0 0 0 0)
	)
	(junction
		(at 130.81 207.01)
		(diameter 0)
		(color 0 0 0 0)
	)
	(junction
		(at 71.12 58.42)
		(diameter 0)
		(color 0 0 0 0)
	)
	(junction
		(at 198.12 123.19)
		(diameter 0)
		(color 0 0 0 0)
	)
	(junction
		(at 168.91 54.61)
		(diameter 0)
		(color 0 0 0 0)
	)
	(junction
		(at 220.98 64.77)
		(diameter 0)
		(color 0 0 0 0)
	)
	(junction
		(at 43.18 77.47)
		(diameter 0)
		(color 0 0 0 0)
	)
	(junction
		(at 71.12 137.16)
		(diameter 0)
		(color 0 0 0 0)
	)
	(junction
		(at 120.65 66.04)
		(diameter 0)
		(color 0 0 0 0)
	)
	(junction
		(at 231.14 184.15)
		(diameter 0)
		(color 0 0 0 0)
	)
	(junction
		(at 262.89 146.05)
		(diameter 0)
		(color 0 0 0 0)
	)
	(junction
		(at 198.12 133.35)
		(diameter 0)
		(color 0 0 0 0)
	)
	(junction
		(at 262.89 36.83)
		(diameter 0)
		(color 0 0 0 0)
	)
	(junction
		(at 274.32 36.83)
		(diameter 0)
		(color 0 0 0 0)
	)
	(junction
		(at 160.02 54.61)
		(diameter 0)
		(color 0 0 0 0)
	)
	(junction
		(at 39.37 93.98)
		(diameter 0)
		(color 0 0 0 0)
	)
	(junction
		(at 220.98 54.61)
		(diameter 0)
		(color 0 0 0 0)
	)
	(junction
		(at 208.28 184.15)
		(diameter 0)
		(color 0 0 0 0)
	)
	(junction
		(at 297.18 69.85)
		(diameter 0)
		(color 0 0 0 0)
	)
	(junction
		(at 335.28 118.11)
		(diameter 0)
		(color 0 0 0 0)
	)
	(junction
		(at 168.91 59.69)
		(diameter 0)
		(color 0 0 0 0)
	)
	(junction
		(at 278.13 146.05)
		(diameter 0)
		(color 0 0 0 0)
	)
	(junction
		(at 86.36 58.42)
		(diameter 0)
		(color 0 0 0 0)
	)
	(junction
		(at 342.9 222.25)
		(diameter 0)
		(color 0 0 0 0)
	)
	(junction
		(at 332.74 57.15)
		(diameter 0)
		(color 0 0 0 0)
	)
	(junction
		(at 100.33 196.85)
		(diameter 0)
		(color 0 0 0 0)
	)
	(junction
		(at 330.2 132.08)
		(diameter 0)
		(color 0 0 0 0)
	)
	(junction
		(at 157.48 133.35)
		(diameter 0)
		(color 0 0 0 0)
	)
	(junction
		(at 210.82 54.61)
		(diameter 0)
		(color 0 0 0 0)
	)
	(junction
		(at 365.76 222.25)
		(diameter 0)
		(color 0 0 0 0)
	)
	(junction
		(at 266.7 36.83)
		(diameter 0)
		(color 0 0 0 0)
	)
	(junction
		(at 200.66 184.15)
		(diameter 0)
		(color 0 0 0 0)
	)
	(junction
		(at 293.37 54.61)
		(diameter 0)
		(color 0 0 0 0)
	)
	(junction
		(at 43.18 215.9)
		(diameter 0)
		(color 0 0 0 0)
	)
	(junction
		(at 270.51 146.05)
		(diameter 0)
		(color 0 0 0 0)
	)
	(junction
		(at 85.09 196.85)
		(diameter 0)
		(color 0 0 0 0)
	)
	(junction
		(at 335.28 146.05)
		(diameter 0)
		(color 0 0 0 0)
	)
	(junction
		(at 262.89 54.61)
		(diameter 0)
		(color 0 0 0 0)
	)
	(junction
		(at 335.28 153.67)
		(diameter 0)
		(color 0 0 0 0)
	)
	(junction
		(at 220.98 194.31)
		(diameter 0)
		(color 0 0 0 0)
	)
	(junction
		(at 167.64 184.15)
		(diameter 0)
		(color 0 0 0 0)
	)
	(junction
		(at 194.31 184.15)
		(diameter 0)
		(color 0 0 0 0)
	)
	(junction
		(at 111.76 58.42)
		(diameter 0)
		(color 0 0 0 0)
	)
	(junction
		(at 187.96 123.19)
		(diameter 0)
		(color 0 0 0 0)
	)
	(junction
		(at 313.69 180.34)
		(diameter 0)
		(color 0 0 0 0)
	)
	(junction
		(at 121.92 242.57)
		(diameter 0)
		(color 0 0 0 0)
	)
	(no_connect
		(at 369.57 86.36)
	)
	(no_connect
		(at 369.57 105.41)
	)
	(no_connect
		(at 369.57 110.49)
	)
	(no_connect
		(at 369.57 102.87)
	)
	(no_connect
		(at 369.57 107.95)
	)
	(no_connect
		(at 369.57 119.38)
	)
	(no_connect
		(at 38.1 222.25)
	)
	(no_connect
		(at 369.57 88.9)
	)
	(no_connect
		(at 364.49 190.5)
	)
	(no_connect
		(at 369.57 121.92)
	)
	(no_connect
		(at 369.57 97.79)
	)
	(no_connect
		(at 369.57 127)
	)
	(no_connect
		(at 369.57 54.61)
	)
	(no_connect
		(at 337.82 66.04)
	)
	(no_connect
		(at 369.57 124.46)
	)
	(no_connect
		(at 369.57 64.77)
	)
	(no_connect
		(at 369.57 62.23)
	)
	(no_connect
		(at 369.57 57.15)
	)
	(no_connect
		(at 344.17 190.5)
	)
	(no_connect
		(at 369.57 132.08)
	)
	(no_connect
		(at 38.1 224.79)
	)
	(no_connect
		(at 369.57 81.28)
	)
	(no_connect
		(at 369.57 78.74)
	)
	(no_connect
		(at 149.86 199.39)
	)
	(no_connect
		(at 337.82 63.5)
	)
	(no_connect
		(at 38.1 83.82)
	)
	(no_connect
		(at 369.57 67.31)
	)
	(no_connect
		(at 369.57 59.69)
	)
	(no_connect
		(at 369.57 100.33)
	)
	(no_connect
		(at 38.1 86.36)
	)
	(no_connect
		(at 369.57 129.54)
	)
	(bus_entry
		(at 384.81 49.53)
		(size -2.54 2.54)
		(stroke
			(width 0)
			(type default)
		)
	)
	(bus_entry
		(at 384.81 46.99)
		(size -2.54 2.54)
		(stroke
			(width 0)
			(type default)
		)
	)
	(bus_entry
		(at 394.97 180.34)
		(size -2.54 2.54)
		(stroke
			(width 0)
			(type default)
		)
	)
	(bus_entry
		(at 394.97 182.88)
		(size -2.54 2.54)
		(stroke
			(width 0)
			(type default)
		)
	)
	(bus_entry
		(at 384.81 90.17)
		(size -2.54 2.54)
		(stroke
			(width 0)
			(type default)
		)
	)
	(bus_entry
		(at 379.73 229.87)
		(size -2.54 2.54)
		(stroke
			(width 0)
			(type default)
		)
	)
	(bus_entry
		(at 384.81 111.76)
		(size -2.54 2.54)
		(stroke
			(width 0)
			(type default)
		)
	)
	(bus_entry
		(at 196.85 257.81)
		(size -2.54 2.54)
		(stroke
			(width 0)
			(type default)
		)
	)
	(bus_entry
		(at 379.73 234.95)
		(size -2.54 2.54)
		(stroke
			(width 0)
			(type default)
		)
	)
	(bus_entry
		(at 384.81 92.71)
		(size -2.54 2.54)
		(stroke
			(width 0)
			(type default)
		)
	)
	(bus_entry
		(at 71.12 218.44)
		(size -2.54 -2.54)
		(stroke
			(width 0)
			(type default)
		)
	)
	(bus_entry
		(at 394.97 182.88)
		(size -2.54 2.54)
		(stroke
			(width 0)
			(type default)
		)
	)
	(bus_entry
		(at 71.12 213.36)
		(size -2.54 -2.54)
		(stroke
			(width 0)
			(type default)
		)
	)
	(bus_entry
		(at 322.58 74.93)
		(size 2.54 -2.54)
		(stroke
			(width 0)
			(type default)
		)
	)
	(bus_entry
		(at 322.58 72.39)
		(size 2.54 -2.54)
		(stroke
			(width 0)
			(type default)
		)
	)
	(bus_entry
		(at 394.97 180.34)
		(size -2.54 2.54)
		(stroke
			(width 0)
			(type default)
		)
	)
	(bus_entry
		(at 384.81 114.3)
		(size -2.54 2.54)
		(stroke
			(width 0)
			(type default)
		)
	)
	(bus_entry
		(at 71.12 80.01)
		(size -2.54 -2.54)
		(stroke
			(width 0)
			(type default)
		)
	)
	(bus_entry
		(at 71.12 74.93)
		(size -2.54 -2.54)
		(stroke
			(width 0)
			(type default)
		)
	)
	(bus
		(pts
			(xy 71.12 80.01) (xy 71.12 91.44)
		)
		(stroke
			(width 0)
			(type default)
		)
	)
	(wire
		(pts
			(xy 372.11 198.12) (xy 372.11 200.66)
		)
		(stroke
			(width 0)
			(type default)
		)
	)
	(wire
		(pts
			(xy 198.12 191.77) (xy 198.12 194.31)
		)
		(stroke
			(width 0)
			(type default)
		)
	)
	(wire
		(pts
			(xy 177.8 130.81) (xy 177.8 140.97)
		)
		(stroke
			(width 0)
			(type default)
		)
	)
	(polyline
		(pts
			(xy 107.95 223.52) (xy 259.08 223.52)
		)
		(stroke
			(width 0)
			(type default)
		)
	)
	(wire
		(pts
			(xy 50.8 194.31) (xy 50.8 196.85)
		)
		(stroke
			(width 0)
			(type default)
		)
	)
	(wire
		(pts
			(xy 218.44 54.61) (xy 220.98 54.61)
		)
		(stroke
			(width 0)
			(type default)
		)
	)
	(wire
		(pts
			(xy 160.02 54.61) (xy 168.91 54.61)
		)
		(stroke
			(width 0)
			(type default)
		)
	)
	(wire
		(pts
			(xy 210.82 54.61) (xy 200.66 54.61)
		)
		(stroke
			(width 0)
			(type default)
		)
	)
	(wire
		(pts
			(xy 95.25 80.01) (xy 95.25 83.82)
		)
		(stroke
			(width 0)
			(type default)
		)
	)
	(wire
		(pts
			(xy 57.15 36.83) (xy 67.31 36.83)
		)
		(stroke
			(width 0)
			(type default)
		)
	)
	(wire
		(pts
			(xy 370.84 135.89) (xy 369.57 135.89)
		)
		(stroke
			(width 0)
			(type default)
		)
	)
	(wire
		(pts
			(xy 281.94 60.96) (xy 281.94 62.23)
		)
		(stroke
			(width 0)
			(type default)
		)
	)
	(wire
		(pts
			(xy 231.14 175.26) (xy 231.14 184.15)
		)
		(stroke
			(width 0)
			(type default)
		)
	)
	(wire
		(pts
			(xy 110.49 196.85) (xy 134.62 196.85)
		)
		(stroke
			(width 0)
			(type default)
		)
	)
	(bus
		(pts
			(xy 386.08 109.22) (xy 384.81 109.22)
		)
		(stroke
			(width 0)
			(type default)
		)
	)
	(wire
		(pts
			(xy 266.7 44.45) (xy 266.7 45.72)
		)
		(stroke
			(width 0)
			(type default)
		)
	)
	(wire
		(pts
			(xy 120.65 67.31) (xy 120.65 66.04)
		)
		(stroke
			(width 0)
			(type default)
		)
	)
	(polyline
		(pts
			(xy 147.32 12.7) (xy 147.32 110.49)
		)
		(stroke
			(width 0)
			(type default)
		)
	)
	(bus
		(pts
			(xy 322.58 72.39) (xy 322.58 74.93)
		)
		(stroke
			(width 0)
			(type default)
		)
	)
	(wire
		(pts
			(xy 57.15 31.75) (xy 67.31 31.75)
		)
		(stroke
			(width 0)
			(type default)
		)
	)
	(wire
		(pts
			(xy 71.12 137.16) (xy 71.12 134.62)
		)
		(stroke
			(width 0)
			(type default)
		)
	)
	(wire
		(pts
			(xy 57.15 39.37) (xy 67.31 39.37)
		)
		(stroke
			(width 0)
			(type default)
		)
	)
	(wire
		(pts
			(xy 342.9 194.31) (xy 342.9 193.04)
		)
		(stroke
			(width 0)
			(type default)
		)
	)
	(wire
		(pts
			(xy 300.99 154.94) (xy 300.99 156.21)
		)
		(stroke
			(width 0)
			(type default)
		)
	)
	(wire
		(pts
			(xy 38.1 212.09) (xy 43.18 212.09)
		)
		(stroke
			(width 0)
			(type default)
		)
	)
	(wire
		(pts
			(xy 278.13 146.05) (xy 285.75 146.05)
		)
		(stroke
			(width 0)
			(type default)
		)
	)
	(wire
		(pts
			(xy 273.05 69.85) (xy 279.4 69.85)
		)
		(stroke
			(width 0)
			(type default)
		)
	)
	(wire
		(pts
			(xy 262.89 146.05) (xy 262.89 144.78)
		)
		(stroke
			(width 0)
			(type default)
		)
	)
	(wire
		(pts
			(xy 198.12 184.15) (xy 198.12 186.69)
		)
		(stroke
			(width 0)
			(type default)
		)
	)
	(wire
		(pts
			(xy 340.36 222.25) (xy 340.36 223.52)
		)
		(stroke
			(width 0)
			(type default)
		)
	)
	(wire
		(pts
			(xy 337.82 148.59) (xy 331.47 148.59)
		)
		(stroke
			(width 0)
			(type default)
		)
	)
	(wire
		(pts
			(xy 220.98 201.93) (xy 220.98 203.2)
		)
		(stroke
			(width 0)
			(type default)
		)
	)
	(wire
		(pts
			(xy 372.11 161.29) (xy 372.11 163.83)
		)
		(stroke
			(width 0)
			(type default)
		)
	)
	(wire
		(pts
			(xy 52.07 194.31) (xy 50.8 194.31)
		)
		(stroke
			(width 0)
			(type default)
		)
	)
	(wire
		(pts
			(xy 80.01 207.01) (xy 80.01 204.47)
		)
		(stroke
			(width 0)
			(type default)
		)
	)
	(wire
		(pts
			(xy 177.8 125.73) (xy 177.8 123.19)
		)
		(stroke
			(width 0)
			(type default)
		)
	)
	(wire
		(pts
			(xy 59.69 77.47) (xy 68.58 77.47)
		)
		(stroke
			(width 0)
			(type default)
		)
	)
	(wire
		(pts
			(xy 143.51 35.56) (xy 111.76 35.56)
		)
		(stroke
			(width 0)
			(type default)
		)
	)
	(wire
		(pts
			(xy 168.91 68.58) (xy 168.91 66.04)
		)
		(stroke
			(width 0)
			(type default)
		)
	)
	(wire
		(pts
			(xy 332.74 105.41) (xy 332.74 104.14)
		)
		(stroke
			(width 0)
			(type default)
		)
	)
	(wire
		(pts
			(xy 167.64 184.15) (xy 194.31 184.15)
		)
		(stroke
			(width 0)
			(type default)
		)
	)
	(wire
		(pts
			(xy 365.76 193.04) (xy 364.49 193.04)
		)
		(stroke
			(width 0)
			(type default)
		)
	)
	(wire
		(pts
			(xy 335.28 143.51) (xy 335.28 146.05)
		)
		(stroke
			(width 0)
			(type default)
		)
	)
	(wire
		(pts
			(xy 168.91 54.61) (xy 180.34 54.61)
		)
		(stroke
			(width 0)
			(type default)
		)
	)
	(wire
		(pts
			(xy 220.98 62.23) (xy 220.98 64.77)
		)
		(stroke
			(width 0)
			(type default)
		)
	)
	(wire
		(pts
			(xy 317.5 127) (xy 317.5 132.08)
		)
		(stroke
			(width 0)
			(type default)
		)
	)
	(wire
		(pts
			(xy 243.84 194.31) (xy 231.14 194.31)
		)
		(stroke
			(width 0)
			(type default)
		)
	)
	(wire
		(pts
			(xy 71.12 129.54) (xy 71.12 127)
		)
		(stroke
			(width 0)
			(type default)
		)
	)
	(wire
		(pts
			(xy 80.01 195.58) (xy 80.01 196.85)
		)
		(stroke
			(width 0)
			(type default)
		)
	)
	(wire
		(pts
			(xy 39.37 229.87) (xy 39.37 232.41)
		)
		(stroke
			(width 0)
			(type default)
		)
	)
	(wire
		(pts
			(xy 168.91 59.69) (xy 180.34 59.69)
		)
		(stroke
			(width 0)
			(type default)
		)
	)
	(wire
		(pts
			(xy 369.57 146.05) (xy 370.84 146.05)
		)
		(stroke
			(width 0)
			(type default)
		)
	)
	(wire
		(pts
			(xy 64.77 237.49) (xy 54.61 237.49)
		)
		(stroke
			(width 0)
			(type default)
		)
	)
	(wire
		(pts
			(xy 71.12 137.16) (xy 77.47 137.16)
		)
		(stroke
			(width 0)
			(type default)
		)
	)
	(wire
		(pts
			(xy 130.81 199.39) (xy 130.81 200.66)
		)
		(stroke
			(width 0)
			(type default)
		)
	)
	(wire
		(pts
			(xy 299.72 69.85) (xy 299.72 71.12)
		)
		(stroke
			(width 0)
			(type default)
		)
	)
	(wire
		(pts
			(xy 304.8 52.07) (xy 337.82 52.07)
		)
		(stroke
			(width 0)
			(type default)
		)
	)
	(wire
		(pts
			(xy 95.25 83.82) (xy 96.52 83.82)
		)
		(stroke
			(width 0)
			(type default)
		)
	)
	(wire
		(pts
			(xy 336.55 85.09) (xy 337.82 85.09)
		)
		(stroke
			(width 0)
			(type default)
		)
	)
	(wire
		(pts
			(xy 304.8 57.15) (xy 304.8 69.85)
		)
		(stroke
			(width 0)
			(type default)
		)
	)
	(wire
		(pts
			(xy 157.48 184.15) (xy 167.64 184.15)
		)
		(stroke
			(width 0)
			(type default)
		)
	)
	(wire
		(pts
			(xy 147.32 133.35) (xy 147.32 137.16)
		)
		(stroke
			(width 0)
			(type default)
		)
	)
	(polyline
		(pts
			(xy 256.54 156.21) (xy 256.54 12.7)
		)
		(stroke
			(width 0)
			(type default)
		)
	)
	(wire
		(pts
			(xy 365.76 242.57) (xy 364.49 242.57)
		)
		(stroke
			(width 0)
			(type default)
		)
	)
	(wire
		(pts
			(xy 147.32 133.35) (xy 157.48 133.35)
		)
		(stroke
			(width 0)
			(type default)
		)
	)
	(wire
		(pts
			(xy 110.49 262.89) (xy 129.54 262.89)
		)
		(stroke
			(width 0)
			(type default)
		)
	)
	(wire
		(pts
			(xy 92.71 196.85) (xy 92.71 199.39)
		)
		(stroke
			(width 0)
			(type default)
		)
	)
	(wire
		(pts
			(xy 243.84 54.61) (xy 243.84 55.88)
		)
		(stroke
			(width 0)
			(type default)
		)
	)
	(wire
		(pts
			(xy 128.27 267.97) (xy 128.27 273.05)
		)
		(stroke
			(width 0)
			(type default)
		)
	)
	(wire
		(pts
			(xy 85.09 196.85) (xy 85.09 199.39)
		)
		(stroke
			(width 0)
			(type default)
		)
	)
	(bus
		(pts
			(xy 71.12 218.44) (xy 71.12 224.79)
		)
		(stroke
			(width 0)
			(type default)
		)
	)
	(wire
		(pts
			(xy 337.82 123.19) (xy 317.5 123.19)
		)
		(stroke
			(width 0)
			(type default)
		)
	)
	(wire
		(pts
			(xy 384.81 162.56) (xy 384.81 163.83)
		)
		(stroke
			(width 0)
			(type default)
		)
	)
	(wire
		(pts
			(xy 369.57 143.51) (xy 392.43 143.51)
		)
		(stroke
			(width 0)
			(type default)
		)
	)
	(wire
		(pts
			(xy 369.57 153.67) (xy 370.84 153.67)
		)
		(stroke
			(width 0)
			(type default)
		)
	)
	(wire
		(pts
			(xy 210.82 59.69) (xy 210.82 54.61)
		)
		(stroke
			(width 0)
			(type default)
		)
	)
	(wire
		(pts
			(xy 336.55 232.41) (xy 344.17 232.41)
		)
		(stroke
			(width 0)
			(type default)
		)
	)
	(wire
		(pts
			(xy 243.84 191.77) (xy 243.84 194.31)
		)
		(stroke
			(width 0)
			(type default)
		)
	)
	(wire
		(pts
			(xy 337.82 127) (xy 317.5 127)
		)
		(stroke
			(width 0)
			(type default)
		)
	)
	(wire
		(pts
			(xy 95.25 66.04) (xy 95.25 58.42)
		)
		(stroke
			(width 0)
			(type default)
		)
	)
	(wire
		(pts
			(xy 50.8 196.85) (xy 80.01 196.85)
		)
		(stroke
			(width 0)
			(type default)
		)
	)
	(wire
		(pts
			(xy 110.49 196.85) (xy 110.49 243.84)
		)
		(stroke
			(width 0)
			(type default)
		)
	)
	(wire
		(pts
			(xy 365.76 215.9) (xy 365.76 217.17)
		)
		(stroke
			(width 0)
			(type default)
		)
	)
	(wire
		(pts
			(xy 289.56 76.2) (xy 289.56 77.47)
		)
		(stroke
			(width 0)
			(type default)
		)
	)
	(wire
		(pts
			(xy 59.69 72.39) (xy 68.58 72.39)
		)
		(stroke
			(width 0)
			(type default)
		)
	)
	(wire
		(pts
			(xy 85.09 196.85) (xy 92.71 196.85)
		)
		(stroke
			(width 0)
			(type default)
		)
	)
	(wire
		(pts
			(xy 231.14 54.61) (xy 234.95 54.61)
		)
		(stroke
			(width 0)
			(type default)
		)
	)
	(wire
		(pts
			(xy 262.89 36.83) (xy 262.89 54.61)
		)
		(stroke
			(width 0)
			(type default)
		)
	)
	(wire
		(pts
			(xy 120.65 77.47) (xy 120.65 78.74)
		)
		(stroke
			(width 0)
			(type default)
		)
	)
	(wire
		(pts
			(xy 281.94 54.61) (xy 281.94 55.88)
		)
		(stroke
			(width 0)
			(type default)
		)
	)
	(wire
		(pts
			(xy 187.96 140.97) (xy 191.77 140.97)
		)
		(stroke
			(width 0)
			(type default)
		)
	)
	(wire
		(pts
			(xy 344.17 227.33) (xy 342.9 227.33)
		)
		(stroke
			(width 0)
			(type default)
		)
	)
	(wire
		(pts
			(xy 85.09 207.01) (xy 85.09 204.47)
		)
		(stroke
			(width 0)
			(type default)
		)
	)
	(wire
		(pts
			(xy 153.67 53.34) (xy 153.67 54.61)
		)
		(stroke
			(width 0)
			(type default)
		)
	)
	(wire
		(pts
			(xy 92.71 78.74) (xy 92.71 80.01)
		)
		(stroke
			(width 0)
			(type default)
		)
	)
	(wire
		(pts
			(xy 43.18 215.9) (xy 43.18 217.17)
		)
		(stroke
			(width 0)
			(type default)
		)
	)
	(wire
		(pts
			(xy 365.76 243.84) (xy 365.76 242.57)
		)
		(stroke
			(width 0)
			(type default)
		)
	)
	(wire
		(pts
			(xy 328.93 171.45) (xy 328.93 172.72)
		)
		(stroke
			(width 0)
			(type default)
		)
	)
	(wire
		(pts
			(xy 367.03 177.8) (xy 364.49 177.8)
		)
		(stroke
			(width 0)
			(type default)
		)
	)
	(wire
		(pts
			(xy 160.02 262.89) (xy 161.29 262.89)
		)
		(stroke
			(width 0)
			(type default)
		)
	)
	(wire
		(pts
			(xy 335.28 153.67) (xy 335.28 156.21)
		)
		(stroke
			(width 0)
			(type default)
		)
	)
	(wire
		(pts
			(xy 281.94 36.83) (xy 281.94 39.37)
		)
		(stroke
			(width 0)
			(type default)
		)
	)
	(wire
		(pts
			(xy 176.53 135.89) (xy 187.96 135.89)
		)
		(stroke
			(width 0)
			(type default)
		)
	)
	(bus
		(pts
			(xy 196.85 257.81) (xy 198.12 257.81)
		)
		(stroke
			(width 0)
			(type default)
		)
	)
	(wire
		(pts
			(xy 157.48 140.97) (xy 157.48 142.24)
		)
		(stroke
			(width 0)
			(type default)
		)
	)
	(wire
		(pts
			(xy 281.94 22.86) (xy 306.07 22.86)
		)
		(stroke
			(width 0)
			(type default)
		)
	)
	(wire
		(pts
			(xy 215.9 175.26) (xy 208.28 175.26)
		)
		(stroke
			(width 0)
			(type default)
		)
	)
	(wire
		(pts
			(xy 297.18 68.58) (xy 297.18 69.85)
		)
		(stroke
			(width 0)
			(type default)
		)
	)
	(wire
		(pts
			(xy 243.84 69.85) (xy 243.84 72.39)
		)
		(stroke
			(width 0)
			(type default)
		)
	)
	(wire
		(pts
			(xy 39.37 91.44) (xy 39.37 93.98)
		)
		(stroke
			(width 0)
			(type default)
		)
	)
	(wire
		(pts
			(xy 100.33 198.12) (xy 100.33 196.85)
		)
		(stroke
			(width 0)
			(type default)
		)
	)
	(wire
		(pts
			(xy 187.96 125.73) (xy 187.96 123.19)
		)
		(stroke
			(width 0)
			(type default)
		)
	)
	(wire
		(pts
			(xy 331.47 154.94) (xy 331.47 156.21)
		)
		(stroke
			(width 0)
			(type default)
		)
	)
	(wire
		(pts
			(xy 167.64 200.66) (xy 167.64 201.93)
		)
		(stroke
			(width 0)
			(type default)
		)
	)
	(wire
		(pts
			(xy 313.69 241.3) (xy 313.69 240.03)
		)
		(stroke
			(width 0)
			(type default)
		)
	)
	(wire
		(pts
			(xy 208.28 184.15) (xy 213.36 184.15)
		)
		(stroke
			(width 0)
			(type default)
		)
	)
	(wire
		(pts
			(xy 64.77 240.03) (xy 54.61 240.03)
		)
		(stroke
			(width 0)
			(type default)
		)
	)
	(wire
		(pts
			(xy 295.91 36.83) (xy 297.18 36.83)
		)
		(stroke
			(width 0)
			(type default)
		)
	)
	(wire
		(pts
			(xy 200.66 59.69) (xy 203.2 59.69)
		)
		(stroke
			(width 0)
			(type default)
		)
	)
	(wire
		(pts
			(xy 208.28 59.69) (xy 210.82 59.69)
		)
		(stroke
			(width 0)
			(type default)
		)
	)
	(wire
		(pts
			(xy 111.76 58.42) (xy 118.11 58.42)
		)
		(stroke
			(width 0.5)
			(type default)
		)
	)
	(wire
		(pts
			(xy 289.56 69.85) (xy 297.18 69.85)
		)
		(stroke
			(width 0)
			(type default)
		)
	)
	(polyline
		(pts
			(xy 307.34 102.87) (xy 307.34 12.7)
		)
		(stroke
			(width 0)
			(type default)
		)
	)
	(wire
		(pts
			(xy 317.5 132.08) (xy 320.04 132.08)
		)
		(stroke
			(width 0)
			(type default)
		)
	)
	(wire
		(pts
			(xy 325.12 229.87) (xy 325.12 231.14)
		)
		(stroke
			(width 0)
			(type default)
		)
	)
	(wire
		(pts
			(xy 231.14 184.15) (xy 231.14 186.69)
		)
		(stroke
			(width 0)
			(type default)
		)
	)
	(wire
		(pts
			(xy 367.03 176.53) (xy 367.03 177.8)
		)
		(stroke
			(width 0)
			(type default)
		)
	)
	(bus
		(pts
			(xy 384.81 111.76) (xy 384.81 114.3)
		)
		(stroke
			(width 0)
			(type default)
		)
	)
	(wire
		(pts
			(xy 262.89 22.86) (xy 269.24 22.86)
		)
		(stroke
			(width 0)
			(type default)
		)
	)
	(wire
		(pts
			(xy 325.12 72.39) (xy 337.82 72.39)
		)
		(stroke
			(width 0)
			(type default)
		)
	)
	(wire
		(pts
			(xy 128.27 242.57) (xy 128.27 252.73)
		)
		(stroke
			(width 0)
			(type default)
		)
	)
	(wire
		(pts
			(xy 100.33 203.2) (xy 100.33 205.74)
		)
		(stroke
			(width 0)
			(type default)
		)
	)
	(wire
		(pts
			(xy 64.77 234.95) (xy 54.61 234.95)
		)
		(stroke
			(width 0)
			(type default)
		)
	)
	(wire
		(pts
			(xy 153.67 54.61) (xy 160.02 54.61)
		)
		(stroke
			(width 0)
			(type default)
		)
	)
	(wire
		(pts
			(xy 328.93 177.8) (xy 328.93 180.34)
		)
		(stroke
			(width 0)
			(type default)
		)
	)
	(wire
		(pts
			(xy 179.07 64.77) (xy 180.34 64.77)
		)
		(stroke
			(width 0)
			(type default)
		)
	)
	(wire
		(pts
			(xy 121.92 241.3) (xy 121.92 242.57)
		)
		(stroke
			(width 0)
			(type default)
		)
	)
	(wire
		(pts
			(xy 243.84 54.61) (xy 250.19 54.61)
		)
		(stroke
			(width 0)
			(type default)
		)
	)
	(wire
		(pts
			(xy 151.13 184.15) (xy 157.48 184.15)
		)
		(stroke
			(width 0)
			(type default)
		)
	)
	(wire
		(pts
			(xy 128.27 242.57) (xy 121.92 242.57)
		)
		(stroke
			(width 0)
			(type default)
		)
	)
	(wire
		(pts
			(xy 160.02 260.35) (xy 172.72 260.35)
		)
		(stroke
			(width 0)
			(type default)
		)
	)
	(wire
		(pts
			(xy 177.8 140.97) (xy 182.88 140.97)
		)
		(stroke
			(width 0)
			(type default)
		)
	)
	(wire
		(pts
			(xy 289.56 36.83) (xy 289.56 39.37)
		)
		(stroke
			(width 0)
			(type default)
		)
	)
	(wire
		(pts
			(xy 71.12 66.04) (xy 71.12 64.77)
		)
		(stroke
			(width 0)
			(type default)
		)
	)
	(wire
		(pts
			(xy 274.32 54.61) (xy 281.94 54.61)
		)
		(stroke
			(width 0)
			(type default)
		)
	)
	(wire
		(pts
			(xy 220.98 54.61) (xy 220.98 57.15)
		)
		(stroke
			(width 0)
			(type default)
		)
	)
	(wire
		(pts
			(xy 289.56 44.45) (xy 289.56 45.72)
		)
		(stroke
			(width 0)
			(type default)
		)
	)
	(wire
		(pts
			(xy 281.94 54.61) (xy 293.37 54.61)
		)
		(stroke
			(width 0)
			(type default)
		)
	)
	(wire
		(pts
			(xy 336.55 185.42) (xy 344.17 185.42)
		)
		(stroke
			(width 0)
			(type default)
		)
	)
	(wire
		(pts
			(xy 149.86 201.93) (xy 167.64 201.93)
		)
		(stroke
			(width 0)
			(type default)
		)
	)
	(wire
		(pts
			(xy 43.18 217.17) (xy 38.1 217.17)
		)
		(stroke
			(width 0)
			(type default)
		)
	)
	(wire
		(pts
			(xy 378.46 73.66) (xy 369.57 73.66)
		)
		(stroke
			(width 0)
			(type default)
		)
	)
	(polyline
		(pts
			(xy 49.53 12.7) (xy 49.53 265.43)
		)
		(stroke
			(width 0)
			(type default)
		)
	)
	(wire
		(pts
			(xy 335.28 177.8) (xy 344.17 177.8)
		)
		(stroke
			(width 0)
			(type default)
		)
	)
	(wire
		(pts
			(xy 85.09 196.85) (xy 80.01 196.85)
		)
		(stroke
			(width 0)
			(type default)
		)
	)
	(wire
		(pts
			(xy 274.32 22.86) (xy 281.94 22.86)
		)
		(stroke
			(width 0)
			(type default)
		)
	)
	(wire
		(pts
			(xy 337.82 151.13) (xy 335.28 151.13)
		)
		(stroke
			(width 0)
			(type default)
		)
	)
	(wire
		(pts
			(xy 281.94 36.83) (xy 289.56 36.83)
		)
		(stroke
			(width 0)
			(type default)
		)
	)
	(wire
		(pts
			(xy 77.47 137.16) (xy 77.47 135.89)
		)
		(stroke
			(width 0)
			(type default)
		)
	)
	(wire
		(pts
			(xy 86.36 58.42) (xy 95.25 58.42)
		)
		(stroke
			(width 0.5)
			(type default)
		)
	)
	(wire
		(pts
			(xy 335.28 151.13) (xy 335.28 153.67)
		)
		(stroke
			(width 0)
			(type default)
		)
	)
	(wire
		(pts
			(xy 278.13 154.94) (xy 278.13 156.21)
		)
		(stroke
			(width 0)
			(type default)
		)
	)
	(polyline
		(pts
			(xy 180.34 156.21) (xy 180.34 223.52)
		)
		(stroke
			(width 0)
			(type default)
		)
	)
	(wire
		(pts
			(xy 284.48 69.85) (xy 289.56 69.85)
		)
		(stroke
			(width 0)
			(type default)
		)
	)
	(wire
		(pts
			(xy 63.5 242.57) (xy 63.5 245.11)
		)
		(stroke
			(width 0)
			(type default)
		)
	)
	(wire
		(pts
			(xy 335.28 153.67) (xy 337.82 153.67)
		)
		(stroke
			(width 0)
			(type default)
		)
	)
	(wire
		(pts
			(xy 198.12 133.35) (xy 208.28 133.35)
		)
		(stroke
			(width 0)
			(type default)
		)
	)
	(polyline
		(pts
			(xy 107.95 12.7) (xy 107.95 283.21)
		)
		(stroke
			(width 0)
			(type default)
		)
	)
	(wire
		(pts
			(xy 370.84 138.43) (xy 369.57 138.43)
		)
		(stroke
			(width 0)
			(type default)
		)
	)
	(wire
		(pts
			(xy 335.28 116.84) (xy 335.28 118.11)
		)
		(stroke
			(width 0)
			(type default)
		)
	)
	(wire
		(pts
			(xy 327.66 132.08) (xy 330.2 132.08)
		)
		(stroke
			(width 0)
			(type default)
		)
	)
	(wire
		(pts
			(xy 325.12 242.57) (xy 325.12 247.65)
		)
		(stroke
			(width 0)
			(type default)
		)
	)
	(wire
		(pts
			(xy 198.12 123.19) (xy 208.28 123.19)
		)
		(stroke
			(width 0)
			(type default)
		)
	)
	(wire
		(pts
			(xy 129.54 267.97) (xy 128.27 267.97)
		)
		(stroke
			(width 0)
			(type default)
		)
	)
	(wire
		(pts
			(xy 40.64 76.2) (xy 38.1 76.2)
		)
		(stroke
			(width 0)
			(type default)
		)
	)
	(wire
		(pts
			(xy 299.72 76.2) (xy 299.72 77.47)
		)
		(stroke
			(width 0)
			(type default)
		)
	)
	(wire
		(pts
			(xy 331.47 148.59) (xy 331.47 149.86)
		)
		(stroke
			(width 0)
			(type default)
		)
	)
	(wire
		(pts
			(xy 293.37 53.34) (xy 293.37 54.61)
		)
		(stroke
			(width 0)
			(type default)
		)
	)
	(wire
		(pts
			(xy 160.02 66.04) (xy 160.02 68.58)
		)
		(stroke
			(width 0)
			(type default)
		)
	)
	(wire
		(pts
			(xy 304.8 57.15) (xy 332.74 57.15)
		)
		(stroke
			(width 0)
			(type default)
		)
	)
	(wire
		(pts
			(xy 342.9 222.25) (xy 342.9 227.33)
		)
		(stroke
			(width 0)
			(type default)
		)
	)
	(wire
		(pts
			(xy 43.18 73.66) (xy 43.18 77.47)
		)
		(stroke
			(width 0)
			(type default)
		)
	)
	(polyline
		(pts
			(xy 107.95 110.49) (xy 256.54 110.49)
		)
		(stroke
			(width 0)
			(type default)
		)
	)
	(wire
		(pts
			(xy 304.8 69.85) (xy 299.72 69.85)
		)
		(stroke
			(width 0)
			(type default)
		)
	)
	(wire
		(pts
			(xy 365.76 217.17) (xy 364.49 217.17)
		)
		(stroke
			(width 0)
			(type default)
		)
	)
	(wire
		(pts
			(xy 266.7 36.83) (xy 274.32 36.83)
		)
		(stroke
			(width 0)
			(type default)
		)
	)
	(wire
		(pts
			(xy 323.85 138.43) (xy 323.85 137.16)
		)
		(stroke
			(width 0)
			(type default)
		)
	)
	(wire
		(pts
			(xy 369.57 148.59) (xy 370.84 148.59)
		)
		(stroke
			(width 0)
			(type default)
		)
	)
	(wire
		(pts
			(xy 43.18 212.09) (xy 43.18 215.9)
		)
		(stroke
			(width 0)
			(type default)
		)
	)
	(wire
		(pts
			(xy 262.89 149.86) (xy 262.89 146.05)
		)
		(stroke
			(width 0)
			(type default)
		)
	)
	(wire
		(pts
			(xy 191.77 140.97) (xy 191.77 138.43)
		)
		(stroke
			(width 0)
			(type default)
		)
	)
	(wire
		(pts
			(xy 317.5 116.84) (xy 317.5 123.19)
		)
		(stroke
			(width 0)
			(type default)
		)
	)
	(wire
		(pts
			(xy 172.72 250.19) (xy 172.72 260.35)
		)
		(stroke
			(width 0)
			(type default)
		)
	)
	(polyline
		(pts
			(xy 307.34 102.87) (xy 307.34 252.73)
		)
		(stroke
			(width 0)
			(type default)
		)
	)
	(wire
		(pts
			(xy 281.94 44.45) (xy 281.94 45.72)
		)
		(stroke
			(width 0)
			(type default)
		)
	)
	(wire
		(pts
			(xy 198.12 133.35) (xy 198.12 130.81)
		)
		(stroke
			(width 0)
			(type default)
		)
	)
	(wire
		(pts
			(xy 266.7 36.83) (xy 266.7 39.37)
		)
		(stroke
			(width 0)
			(type default)
		)
	)
	(wire
		(pts
			(xy 100.33 196.85) (xy 110.49 196.85)
		)
		(stroke
			(width 0)
			(type default)
		)
	)
	(wire
		(pts
			(xy 325.12 100.33) (xy 337.82 100.33)
		)
		(stroke
			(width 0)
			(type default)
		)
	)
	(bus
		(pts
			(xy 384.81 46.99) (xy 384.81 49.53)
		)
		(stroke
			(width 0)
			(type default)
		)
	)
	(wire
		(pts
			(xy 322.58 110.49) (xy 322.58 111.76)
		)
		(stroke
			(width 0)
			(type default)
		)
	)
	(wire
		(pts
			(xy 40.64 209.55) (xy 40.64 210.82)
		)
		(stroke
			(width 0)
			(type default)
		)
	)
	(wire
		(pts
			(xy 167.64 201.93) (xy 167.64 203.2)
		)
		(stroke
			(width 0)
			(type default)
		)
	)
	(wire
		(pts
			(xy 378.46 76.2) (xy 369.57 76.2)
		)
		(stroke
			(width 0)
			(type default)
		)
	)
	(bus
		(pts
			(xy 386.08 44.45) (xy 384.81 44.45)
		)
		(stroke
			(width 0)
			(type default)
		)
	)
	(wire
		(pts
			(xy 365.76 194.31) (xy 365.76 193.04)
		)
		(stroke
			(width 0)
			(type default)
		)
	)
	(wire
		(pts
			(xy 43.18 78.74) (xy 38.1 78.74)
		)
		(stroke
			(width 0)
			(type default)
		)
	)
	(wire
		(pts
			(xy 332.74 59.69) (xy 332.74 57.15)
		)
		(stroke
			(width 0)
			(type default)
		)
	)
	(wire
		(pts
			(xy 167.64 213.36) (xy 167.64 214.63)
		)
		(stroke
			(width 0)
			(type default)
		)
	)
	(wire
		(pts
			(xy 194.31 186.69) (xy 194.31 184.15)
		)
		(stroke
			(width 0)
			(type default)
		)
	)
	(wire
		(pts
			(xy 121.92 248.92) (xy 121.92 250.19)
		)
		(stroke
			(width 0)
			(type default)
		)
	)
	(wire
		(pts
			(xy 220.98 194.31) (xy 208.28 194.31)
		)
		(stroke
			(width 0)
			(type default)
		)
	)
	(wire
		(pts
			(xy 38.1 232.41) (xy 39.37 232.41)
		)
		(stroke
			(width 0)
			(type default)
		)
	)
	(wire
		(pts
			(xy 172.72 260.35) (xy 179.07 260.35)
		)
		(stroke
			(width 0)
			(type default)
		)
	)
	(wire
		(pts
			(xy 317.5 110.49) (xy 317.5 111.76)
		)
		(stroke
			(width 0)
			(type default)
		)
	)
	(wire
		(pts
			(xy 322.58 116.84) (xy 322.58 120.65)
		)
		(stroke
			(width 0)
			(type default)
		)
	)
	(wire
		(pts
			(xy 160.02 255.27) (xy 168.91 255.27)
		)
		(stroke
			(width 0)
			(type default)
		)
	)
	(wire
		(pts
			(xy 336.55 87.63) (xy 337.82 87.63)
		)
		(stroke
			(width 0)
			(type default)
		)
	)
	(wire
		(pts
			(xy 220.98 64.77) (xy 220.98 66.04)
		)
		(stroke
			(width 0)
			(type default)
		)
	)
	(polyline
		(pts
			(xy 12.7 156.21) (xy 256.54 156.21)
		)
		(stroke
			(width 0.7)
			(type dash)
		)
	)
	(wire
		(pts
			(xy 342.9 222.25) (xy 340.36 222.25)
		)
		(stroke
			(width 0)
			(type default)
		)
	)
	(wire
		(pts
			(xy 200.66 184.15) (xy 208.28 184.15)
		)
		(stroke
			(width 0)
			(type default)
		)
	)
	(wire
		(pts
			(xy 325.12 81.28) (xy 337.82 81.28)
		)
		(stroke
			(width 0)
			(type default)
		)
	)
	(wire
		(pts
			(xy 160.02 265.43) (xy 161.29 265.43)
		)
		(stroke
			(width 0)
			(type default)
		)
	)
	(wire
		(pts
			(xy 38.1 209.55) (xy 40.64 209.55)
		)
		(stroke
			(width 0)
			(type default)
		)
	)
	(wire
		(pts
			(xy 157.48 184.15) (xy 157.48 185.42)
		)
		(stroke
			(width 0)
			(type default)
		)
	)
	(wire
		(pts
			(xy 86.36 58.42) (xy 86.36 59.69)
		)
		(stroke
			(width 0)
			(type default)
		)
	)
	(wire
		(pts
			(xy 119.38 256.54) (xy 129.54 256.54)
		)
		(stroke
			(width 0)
			(type default)
		)
	)
	(wire
		(pts
			(xy 157.48 138.43) (xy 157.48 133.35)
		)
		(stroke
			(width 0)
			(type default)
		)
	)
	(wire
		(pts
			(xy 369.57 49.53) (xy 382.27 49.53)
		)
		(stroke
			(width 0)
			(type default)
		)
	)
	(wire
		(pts
			(xy 313.69 171.45) (xy 313.69 180.34)
		)
		(stroke
			(width 0)
			(type default)
		)
	)
	(wire
		(pts
			(xy 293.37 146.05) (xy 293.37 149.86)
		)
		(stroke
			(width 0)
			(type default)
		)
	)
	(wire
		(pts
			(xy 77.47 58.42) (xy 86.36 58.42)
		)
		(stroke
			(width 0.5)
			(type default)
		)
	)
	(wire
		(pts
			(xy 168.91 255.27) (xy 168.91 250.19)
		)
		(stroke
			(width 0)
			(type default)
		)
	)
	(wire
		(pts
			(xy 143.51 54.61) (xy 143.51 35.56)
		)
		(stroke
			(width 0)
			(type default)
		)
	)
	(wire
		(pts
			(xy 168.91 60.96) (xy 168.91 59.69)
		)
		(stroke
			(width 0)
			(type default)
		)
	)
	(wire
		(pts
			(xy 342.9 193.04) (xy 344.17 193.04)
		)
		(stroke
			(width 0)
			(type default)
		)
	)
	(wire
		(pts
			(xy 332.74 59.69) (xy 337.82 59.69)
		)
		(stroke
			(width 0)
			(type default)
		)
	)
	(wire
		(pts
			(xy 177.8 123.19) (xy 187.96 123.19)
		)
		(stroke
			(width 0)
			(type default)
		)
	)
	(wire
		(pts
			(xy 243.84 184.15) (xy 243.84 186.69)
		)
		(stroke
			(width 0)
			(type default)
		)
	)
	(wire
		(pts
			(xy 231.14 194.31) (xy 220.98 194.31)
		)
		(stroke
			(width 0)
			(type default)
		)
	)
	(wire
		(pts
			(xy 325.12 69.85) (xy 337.82 69.85)
		)
		(stroke
			(width 0)
			(type default)
		)
	)
	(wire
		(pts
			(xy 297.18 36.83) (xy 297.18 39.37)
		)
		(stroke
			(width 0)
			(type default)
		)
	)
	(wire
		(pts
			(xy 129.54 252.73) (xy 128.27 252.73)
		)
		(stroke
			(width 0)
			(type default)
		)
	)
	(wire
		(pts
			(xy 330.2 132.08) (xy 337.82 132.08)
		)
		(stroke
			(width 0)
			(type default)
		)
	)
	(wire
		(pts
			(xy 383.54 185.42) (xy 392.43 185.42)
		)
		(stroke
			(width 0)
			(type default)
		)
	)
	(bus
		(pts
			(xy 394.97 179.07) (xy 394.97 180.34)
		)
		(stroke
			(width 0)
			(type default)
		)
	)
	(wire
		(pts
			(xy 157.48 190.5) (xy 157.48 193.04)
		)
		(stroke
			(width 0)
			(type default)
		)
	)
	(wire
		(pts
			(xy 133.35 201.93) (xy 133.35 207.01)
		)
		(stroke
			(width 0)
			(type default)
		)
	)
	(wire
		(pts
			(xy 38.1 66.04) (xy 48.26 66.04)
		)
		(stroke
			(width 0)
			(type default)
		)
	)
	(wire
		(pts
			(xy 304.8 52.07) (xy 304.8 36.83)
		)
		(stroke
			(width 0)
			(type default)
		)
	)
	(wire
		(pts
			(xy 38.1 58.42) (xy 71.12 58.42)
		)
		(stroke
			(width 0.5)
			(type default)
		)
	)
	(wire
		(pts
			(xy 38.1 93.98) (xy 39.37 93.98)
		)
		(stroke
			(width 0)
			(type default)
		)
	)
	(wire
		(pts
			(xy 281.94 29.21) (xy 281.94 30.48)
		)
		(stroke
			(width 0)
			(type default)
		)
	)
	(wire
		(pts
			(xy 304.8 36.83) (xy 297.18 36.83)
		)
		(stroke
			(width 0)
			(type default)
		)
	)
	(wire
		(pts
			(xy 231.14 54.61) (xy 231.14 60.96)
		)
		(stroke
			(width 0)
			(type default)
		)
	)
	(wire
		(pts
			(xy 38.1 71.12) (xy 40.64 71.12)
		)
		(stroke
			(width 0)
			(type default)
		)
	)
	(bus
		(pts
			(xy 384.81 92.71) (xy 384.81 93.98)
		)
		(stroke
			(width 0)
			(type default)
		)
	)
	(wire
		(pts
			(xy 234.95 66.04) (xy 234.95 72.39)
		)
		(stroke
			(width 0)
			(type default)
		)
	)
	(wire
		(pts
			(xy 176.53 138.43) (xy 191.77 138.43)
		)
		(stroke
			(width 0)
			(type default)
		)
	)
	(wire
		(pts
			(xy 285.75 146.05) (xy 293.37 146.05)
		)
		(stroke
			(width 0)
			(type default)
		)
	)
	(wire
		(pts
			(xy 80.01 196.85) (xy 80.01 199.39)
		)
		(stroke
			(width 0)
			(type default)
		)
	)
	(wire
		(pts
			(xy 295.91 35.56) (xy 295.91 36.83)
		)
		(stroke
			(width 0)
			(type default)
		)
	)
	(wire
		(pts
			(xy 317.5 104.14) (xy 322.58 104.14)
		)
		(stroke
			(width 0)
			(type default)
		)
	)
	(wire
		(pts
			(xy 325.12 231.14) (xy 325.12 232.41)
		)
		(stroke
			(width 0)
			(type default)
		)
	)
	(wire
		(pts
			(xy 57.15 34.29) (xy 67.31 34.29)
		)
		(stroke
			(width 0)
			(type default)
		)
	)
	(wire
		(pts
			(xy 332.74 110.49) (xy 332.74 118.11)
		)
		(stroke
			(width 0)
			(type default)
		)
	)
	(wire
		(pts
			(xy 194.31 194.31) (xy 194.31 191.77)
		)
		(stroke
			(width 0)
			(type default)
		)
	)
	(wire
		(pts
			(xy 313.69 163.83) (xy 313.69 166.37)
		)
		(stroke
			(width 0)
			(type default)
		)
	)
	(wire
		(pts
			(xy 364.49 227.33) (xy 365.76 227.33)
		)
		(stroke
			(width 0)
			(type default)
		)
	)
	(wire
		(pts
			(xy 336.55 237.49) (xy 344.17 237.49)
		)
		(stroke
			(width 0)
			(type default)
		)
	)
	(wire
		(pts
			(xy 179.07 260.35) (xy 179.07 210.82)
		)
		(stroke
			(width 0)
			(type default)
		)
	)
	(wire
		(pts
			(xy 187.96 135.89) (xy 187.96 130.81)
		)
		(stroke
			(width 0)
			(type default)
		)
	)
	(wire
		(pts
			(xy 300.99 146.05) (xy 300.99 149.86)
		)
		(stroke
			(width 0)
			(type default)
		)
	)
	(wire
		(pts
			(xy 325.12 95.25) (xy 337.82 95.25)
		)
		(stroke
			(width 0)
			(type default)
		)
	)
	(wire
		(pts
			(xy 278.13 149.86) (xy 278.13 146.05)
		)
		(stroke
			(width 0)
			(type default)
		)
	)
	(wire
		(pts
			(xy 111.76 64.77) (xy 111.76 66.04)
		)
		(stroke
			(width 0)
			(type default)
		)
	)
	(wire
		(pts
			(xy 208.28 175.26) (xy 208.28 184.15)
		)
		(stroke
			(width 0)
			(type default)
		)
	)
	(wire
		(pts
			(xy 384.81 168.91) (xy 384.81 170.18)
		)
		(stroke
			(width 0)
			(type default)
		)
	)
	(wire
		(pts
			(xy 92.71 73.66) (xy 92.71 66.04)
		)
		(stroke
			(width 0)
			(type default)
		)
	)
	(wire
		(pts
			(xy 383.54 187.96) (xy 383.54 185.42)
		)
		(stroke
			(width 0)
			(type default)
		)
	)
	(wire
		(pts
			(xy 384.81 205.74) (xy 384.81 207.01)
		)
		(stroke
			(width 0)
			(type default)
		)
	)
	(wire
		(pts
			(xy 48.26 204.47) (xy 38.1 204.47)
		)
		(stroke
			(width 0)
			(type default)
		)
	)
	(wire
		(pts
			(xy 297.18 44.45) (xy 297.18 45.72)
		)
		(stroke
			(width 0)
			(type default)
		)
	)
	(wire
		(pts
			(xy 134.62 199.39) (xy 130.81 199.39)
		)
		(stroke
			(width 0)
			(type default)
		)
	)
	(wire
		(pts
			(xy 289.56 69.85) (xy 289.56 71.12)
		)
		(stroke
			(width 0)
			(type default)
		)
	)
	(wire
		(pts
			(xy 220.98 71.12) (xy 220.98 72.39)
		)
		(stroke
			(width 0)
			(type default)
		)
	)
	(wire
		(pts
			(xy 262.89 54.61) (xy 269.24 54.61)
		)
		(stroke
			(width 0)
			(type default)
		)
	)
	(bus
		(pts
			(xy 384.81 44.45) (xy 384.81 46.99)
		)
		(stroke
			(width 0)
			(type default)
		)
	)
	(wire
		(pts
			(xy 160.02 54.61) (xy 160.02 60.96)
		)
		(stroke
			(width 0)
			(type default)
		)
	)
	(wire
		(pts
			(xy 71.12 58.42) (xy 77.47 58.42)
		)
		(stroke
			(width 0.5)
			(type default)
		)
	)
	(wire
		(pts
			(xy 110.49 262.89) (xy 110.49 248.92)
		)
		(stroke
			(width 0)
			(type default)
		)
	)
	(wire
		(pts
			(xy 77.47 137.16) (xy 91.44 137.16)
		)
		(stroke
			(width 0)
			(type default)
		)
	)
	(wire
		(pts
			(xy 86.36 66.04) (xy 86.36 64.77)
		)
		(stroke
			(width 0)
			(type default)
		)
	)
	(polyline
		(pts
			(xy 256.54 156.21) (xy 256.54 283.21)
		)
		(stroke
			(width 0.7)
			(type dash)
		)
	)
	(wire
		(pts
			(xy 274.32 44.45) (xy 274.32 45.72)
		)
		(stroke
			(width 0)
			(type default)
		)
	)
	(wire
		(pts
			(xy 92.71 196.85) (xy 100.33 196.85)
		)
		(stroke
			(width 0)
			(type default)
		)
	)
	(wire
		(pts
			(xy 38.1 73.66) (xy 43.18 73.66)
		)
		(stroke
			(width 0)
			(type default)
		)
	)
	(wire
		(pts
			(xy 77.47 57.15) (xy 77.47 58.42)
		)
		(stroke
			(width 0)
			(type default)
		)
	)
	(wire
		(pts
			(xy 160.02 267.97) (xy 161.29 267.97)
		)
		(stroke
			(width 0)
			(type default)
		)
	)
	(wire
		(pts
			(xy 297.18 69.85) (xy 299.72 69.85)
		)
		(stroke
			(width 0)
			(type default)
		)
	)
	(wire
		(pts
			(xy 121.92 242.57) (xy 121.92 243.84)
		)
		(stroke
			(width 0)
			(type default)
		)
	)
	(wire
		(pts
			(xy 247.65 184.15) (xy 243.84 184.15)
		)
		(stroke
			(width 0)
			(type default)
		)
	)
	(wire
		(pts
			(xy 210.82 54.61) (xy 213.36 54.61)
		)
		(stroke
			(width 0)
			(type default)
		)
	)
	(wire
		(pts
			(xy 365.76 222.25) (xy 368.3 222.25)
		)
		(stroke
			(width 0)
			(type default)
		)
	)
	(wire
		(pts
			(xy 369.57 83.82) (xy 378.46 83.82)
		)
		(stroke
			(width 0)
			(type default)
		)
	)
	(wire
		(pts
			(xy 179.07 210.82) (xy 173.99 210.82)
		)
		(stroke
			(width 0)
			(type default)
		)
	)
	(wire
		(pts
			(xy 328.93 180.34) (xy 344.17 180.34)
		)
		(stroke
			(width 0)
			(type default)
		)
	)
	(wire
		(pts
			(xy 313.69 246.38) (xy 313.69 247.65)
		)
		(stroke
			(width 0)
			(type default)
		)
	)
	(wire
		(pts
			(xy 344.17 242.57) (xy 328.93 242.57)
		)
		(stroke
			(width 0)
			(type default)
		)
	)
	(wire
		(pts
			(xy 336.55 182.88) (xy 344.17 182.88)
		)
		(stroke
			(width 0)
			(type default)
		)
	)
	(wire
		(pts
			(xy 337.82 57.15) (xy 332.74 57.15)
		)
		(stroke
			(width 0)
			(type default)
		)
	)
	(wire
		(pts
			(xy 39.37 93.98) (xy 39.37 97.79)
		)
		(stroke
			(width 0)
			(type default)
		)
	)
	(wire
		(pts
			(xy 43.18 77.47) (xy 49.53 77.47)
		)
		(stroke
			(width 0)
			(type default)
		)
	)
	(wire
		(pts
			(xy 38.1 91.44) (xy 39.37 91.44)
		)
		(stroke
			(width 0)
			(type default)
		)
	)
	(wire
		(pts
			(xy 220.98 194.31) (xy 220.98 196.85)
		)
		(stroke
			(width 0)
			(type default)
		)
	)
	(wire
		(pts
			(xy 322.58 104.14) (xy 332.74 104.14)
		)
		(stroke
			(width 0)
			(type default)
		)
	)
	(wire
		(pts
			(xy 130.81 207.01) (xy 133.35 207.01)
		)
		(stroke
			(width 0)
			(type default)
		)
	)
	(wire
		(pts
			(xy 262.89 69.85) (xy 262.89 54.61)
		)
		(stroke
			(width 0)
			(type default)
		)
	)
	(wire
		(pts
			(xy 59.69 215.9) (xy 68.58 215.9)
		)
		(stroke
			(width 0)
			(type default)
		)
	)
	(wire
		(pts
			(xy 335.28 146.05) (xy 337.82 146.05)
		)
		(stroke
			(width 0)
			(type default)
		)
	)
	(wire
		(pts
			(xy 364.49 237.49) (xy 377.19 237.49)
		)
		(stroke
			(width 0)
			(type default)
		)
	)
	(wire
		(pts
			(xy 92.71 207.01) (xy 92.71 204.47)
		)
		(stroke
			(width 0)
			(type default)
		)
	)
	(wire
		(pts
			(xy 157.48 140.97) (xy 160.02 140.97)
		)
		(stroke
			(width 0)
			(type default)
		)
	)
	(wire
		(pts
			(xy 365.76 222.25) (xy 364.49 222.25)
		)
		(stroke
			(width 0)
			(type default)
		)
	)
	(wire
		(pts
			(xy 300.99 146.05) (xy 335.28 146.05)
		)
		(stroke
			(width 0)
			(type default)
		)
	)
	(wire
		(pts
			(xy 168.91 241.3) (xy 168.91 245.11)
		)
		(stroke
			(width 0)
			(type default)
		)
	)
	(bus
		(pts
			(xy 394.97 180.34) (xy 394.97 182.88)
		)
		(stroke
			(width 0)
			(type default)
		)
	)
	(wire
		(pts
			(xy 100.33 210.82) (xy 100.33 213.36)
		)
		(stroke
			(width 0)
			(type default)
		)
	)
	(wire
		(pts
			(xy 364.49 232.41) (xy 377.19 232.41)
		)
		(stroke
			(width 0)
			(type default)
		)
	)
	(wire
		(pts
			(xy 289.56 36.83) (xy 295.91 36.83)
		)
		(stroke
			(width 0)
			(type default)
		)
	)
	(wire
		(pts
			(xy 176.53 133.35) (xy 198.12 133.35)
		)
		(stroke
			(width 0)
			(type default)
		)
	)
	(wire
		(pts
			(xy 322.58 120.65) (xy 337.82 120.65)
		)
		(stroke
			(width 0)
			(type default)
		)
	)
	(wire
		(pts
			(xy 234.95 54.61) (xy 234.95 60.96)
		)
		(stroke
			(width 0)
			(type default)
		)
	)
	(wire
		(pts
			(xy 130.81 207.01) (xy 130.81 208.28)
		)
		(stroke
			(width 0)
			(type default)
		)
	)
	(wire
		(pts
			(xy 313.69 180.34) (xy 328.93 180.34)
		)
		(stroke
			(width 0)
			(type default)
		)
	)
	(wire
		(pts
			(xy 285.75 149.86) (xy 285.75 146.05)
		)
		(stroke
			(width 0)
			(type default)
		)
	)
	(wire
		(pts
			(xy 71.12 139.7) (xy 71.12 137.16)
		)
		(stroke
			(width 0)
			(type default)
		)
	)
	(wire
		(pts
			(xy 337.82 143.51) (xy 335.28 143.51)
		)
		(stroke
			(width 0)
			(type default)
		)
	)
	(wire
		(pts
			(xy 40.64 72.39) (xy 49.53 72.39)
		)
		(stroke
			(width 0)
			(type default)
		)
	)
	(wire
		(pts
			(xy 38.1 229.87) (xy 39.37 229.87)
		)
		(stroke
			(width 0)
			(type default)
		)
	)
	(bus
		(pts
			(xy 379.73 227.33) (xy 379.73 229.87)
		)
		(stroke
			(width 0)
			(type default)
		)
	)
	(bus
		(pts
			(xy 386.08 87.63) (xy 384.81 87.63)
		)
		(stroke
			(width 0)
			(type default)
		)
	)
	(wire
		(pts
			(xy 128.27 58.42) (xy 134.62 58.42)
		)
		(stroke
			(width 0.5)
			(type default)
		)
	)
	(wire
		(pts
			(xy 48.26 201.93) (xy 38.1 201.93)
		)
		(stroke
			(width 0)
			(type default)
		)
	)
	(wire
		(pts
			(xy 262.89 146.05) (xy 270.51 146.05)
		)
		(stroke
			(width 0)
			(type default)
		)
	)
	(wire
		(pts
			(xy 140.97 74.93) (xy 127 74.93)
		)
		(stroke
			(width 0)
			(type default)
		)
	)
	(wire
		(pts
			(xy 198.12 184.15) (xy 200.66 184.15)
		)
		(stroke
			(width 0)
			(type default)
		)
	)
	(wire
		(pts
			(xy 372.11 168.91) (xy 372.11 170.18)
		)
		(stroke
			(width 0)
			(type default)
		)
	)
	(wire
		(pts
			(xy 364.49 187.96) (xy 383.54 187.96)
		)
		(stroke
			(width 0)
			(type default)
		)
	)
	(wire
		(pts
			(xy 372.11 205.74) (xy 372.11 207.01)
		)
		(stroke
			(width 0)
			(type default)
		)
	)
	(wire
		(pts
			(xy 328.93 231.14) (xy 325.12 231.14)
		)
		(stroke
			(width 0)
			(type default)
		)
	)
	(wire
		(pts
			(xy 369.57 52.07) (xy 382.27 52.07)
		)
		(stroke
			(width 0)
			(type default)
		)
	)
	(wire
		(pts
			(xy 223.52 184.15) (xy 231.14 184.15)
		)
		(stroke
			(width 0)
			(type default)
		)
	)
	(wire
		(pts
			(xy 243.84 50.8) (xy 243.84 54.61)
		)
		(stroke
			(width 0)
			(type default)
		)
	)
	(wire
		(pts
			(xy 71.12 58.42) (xy 71.12 59.69)
		)
		(stroke
			(width 0)
			(type default)
		)
	)
	(wire
		(pts
			(xy 335.28 217.17) (xy 344.17 217.17)
		)
		(stroke
			(width 0)
			(type default)
		)
	)
	(polyline
		(pts
			(xy 49.53 110.49) (xy 107.95 110.49)
		)
		(stroke
			(width 0)
			(type default)
		)
	)
	(wire
		(pts
			(xy 120.65 64.77) (xy 120.65 66.04)
		)
		(stroke
			(width 0)
			(type default)
		)
	)
	(wire
		(pts
			(xy 191.77 138.43) (xy 208.28 138.43)
		)
		(stroke
			(width 0)
			(type default)
		)
	)
	(wire
		(pts
			(xy 220.98 190.5) (xy 220.98 194.31)
		)
		(stroke
			(width 0)
			(type default)
		)
	)
	(wire
		(pts
			(xy 243.84 184.15) (xy 231.14 184.15)
		)
		(stroke
			(width 0)
			(type default)
		)
	)
	(wire
		(pts
			(xy 384.81 199.39) (xy 384.81 200.66)
		)
		(stroke
			(width 0)
			(type default)
		)
	)
	(wire
		(pts
			(xy 317.5 102.87) (xy 317.5 104.14)
		)
		(stroke
			(width 0)
			(type default)
		)
	)
	(wire
		(pts
			(xy 375.92 185.42) (xy 383.54 185.42)
		)
		(stroke
			(width 0)
			(type default)
		)
	)
	(wire
		(pts
			(xy 138.43 133.35) (xy 147.32 133.35)
		)
		(stroke
			(width 0)
			(type default)
		)
	)
	(wire
		(pts
			(xy 40.64 71.12) (xy 40.64 72.39)
		)
		(stroke
			(width 0)
			(type default)
		)
	)
	(wire
		(pts
			(xy 285.75 154.94) (xy 285.75 156.21)
		)
		(stroke
			(width 0)
			(type default)
		)
	)
	(wire
		(pts
			(xy 300.99 146.05) (xy 293.37 146.05)
		)
		(stroke
			(width 0)
			(type default)
		)
	)
	(wire
		(pts
			(xy 378.46 71.12) (xy 369.57 71.12)
		)
		(stroke
			(width 0)
			(type default)
		)
	)
	(wire
		(pts
			(xy 160.02 252.73) (xy 161.29 252.73)
		)
		(stroke
			(width 0)
			(type default)
		)
	)
	(bus
		(pts
			(xy 379.73 229.87) (xy 379.73 234.95)
		)
		(stroke
			(width 0)
			(type default)
		)
	)
	(wire
		(pts
			(xy 262.89 36.83) (xy 266.7 36.83)
		)
		(stroke
			(width 0)
			(type default)
		)
	)
	(wire
		(pts
			(xy 157.48 133.35) (xy 160.02 133.35)
		)
		(stroke
			(width 0)
			(type default)
		)
	)
	(wire
		(pts
			(xy 369.57 114.3) (xy 382.27 114.3)
		)
		(stroke
			(width 0)
			(type default)
		)
	)
	(wire
		(pts
			(xy 364.49 182.88) (xy 392.43 182.88)
		)
		(stroke
			(width 0)
			(type default)
		)
	)
	(wire
		(pts
			(xy 281.94 22.86) (xy 281.94 24.13)
		)
		(stroke
			(width 0)
			(type default)
		)
	)
	(wire
		(pts
			(xy 270.51 146.05) (xy 278.13 146.05)
		)
		(stroke
			(width 0)
			(type default)
		)
	)
	(wire
		(pts
			(xy 198.12 123.19) (xy 198.12 125.73)
		)
		(stroke
			(width 0)
			(type default)
		)
	)
	(wire
		(pts
			(xy 64.77 232.41) (xy 54.61 232.41)
		)
		(stroke
			(width 0)
			(type default)
		)
	)
	(wire
		(pts
			(xy 328.93 242.57) (xy 328.93 231.14)
		)
		(stroke
			(width 0)
			(type default)
		)
	)
	(wire
		(pts
			(xy 325.12 76.2) (xy 337.82 76.2)
		)
		(stroke
			(width 0)
			(type default)
		)
	)
	(wire
		(pts
			(xy 369.57 95.25) (xy 382.27 95.25)
		)
		(stroke
			(width 0)
			(type default)
		)
	)
	(wire
		(pts
			(xy 220.98 54.61) (xy 231.14 54.61)
		)
		(stroke
			(width 0)
			(type default)
		)
	)
	(wire
		(pts
			(xy 231.14 66.04) (xy 231.14 72.39)
		)
		(stroke
			(width 0)
			(type default)
		)
	)
	(wire
		(pts
			(xy 262.89 69.85) (xy 267.97 69.85)
		)
		(stroke
			(width 0)
			(type default)
		)
	)
	(wire
		(pts
			(xy 172.72 243.84) (xy 172.72 245.11)
		)
		(stroke
			(width 0)
			(type default)
		)
	)
	(wire
		(pts
			(xy 40.64 210.82) (xy 49.53 210.82)
		)
		(stroke
			(width 0)
			(type default)
		)
	)
	(wire
		(pts
			(xy 111.76 58.42) (xy 111.76 59.69)
		)
		(stroke
			(width 0)
			(type default)
		)
	)
	(bus
		(pts
			(xy 71.12 213.36) (xy 71.12 218.44)
		)
		(stroke
			(width 0)
			(type default)
		)
	)
	(wire
		(pts
			(xy 325.12 97.79) (xy 337.82 97.79)
		)
		(stroke
			(width 0)
			(type default)
		)
	)
	(wire
		(pts
			(xy 306.07 49.53) (xy 306.07 22.86)
		)
		(stroke
			(width 0)
			(type default)
		)
	)
	(wire
		(pts
			(xy 255.27 54.61) (xy 262.89 54.61)
		)
		(stroke
			(width 0)
			(type default)
		)
	)
	(wire
		(pts
			(xy 43.18 215.9) (xy 49.53 215.9)
		)
		(stroke
			(width 0)
			(type default)
		)
	)
	(wire
		(pts
			(xy 59.69 210.82) (xy 68.58 210.82)
		)
		(stroke
			(width 0)
			(type default)
		)
	)
	(wire
		(pts
			(xy 187.96 135.89) (xy 208.28 135.89)
		)
		(stroke
			(width 0)
			(type default)
		)
	)
	(wire
		(pts
			(xy 63.5 242.57) (xy 64.77 242.57)
		)
		(stroke
			(width 0)
			(type default)
		)
	)
	(wire
		(pts
			(xy 336.55 187.96) (xy 344.17 187.96)
		)
		(stroke
			(width 0)
			(type default)
		)
	)
	(wire
		(pts
			(xy 335.28 118.11) (xy 337.82 118.11)
		)
		(stroke
			(width 0)
			(type default)
		)
	)
	(wire
		(pts
			(xy 330.2 132.08) (xy 330.2 133.35)
		)
		(stroke
			(width 0)
			(type default)
		)
	)
	(wire
		(pts
			(xy 369.57 92.71) (xy 382.27 92.71)
		)
		(stroke
			(width 0)
			(type default)
		)
	)
	(wire
		(pts
			(xy 231.14 175.26) (xy 220.98 175.26)
		)
		(stroke
			(width 0)
			(type default)
		)
	)
	(wire
		(pts
			(xy 143.51 54.61) (xy 153.67 54.61)
		)
		(stroke
			(width 0)
			(type default)
		)
	)
	(wire
		(pts
			(xy 134.62 201.93) (xy 133.35 201.93)
		)
		(stroke
			(width 0)
			(type default)
		)
	)
	(wire
		(pts
			(xy 130.81 205.74) (xy 130.81 207.01)
		)
		(stroke
			(width 0)
			(type default)
		)
	)
	(wire
		(pts
			(xy 77.47 137.16) (xy 77.47 139.7)
		)
		(stroke
			(width 0)
			(type default)
		)
	)
	(wire
		(pts
			(xy 179.07 68.58) (xy 179.07 64.77)
		)
		(stroke
			(width 0)
			(type default)
		)
	)
	(wire
		(pts
			(xy 231.14 191.77) (xy 231.14 194.31)
		)
		(stroke
			(width 0)
			(type default)
		)
	)
	(bus
		(pts
			(xy 384.81 109.22) (xy 384.81 111.76)
		)
		(stroke
			(width 0)
			(type default)
		)
	)
	(wire
		(pts
			(xy 247.65 182.88) (xy 247.65 184.15)
		)
		(stroke
			(width 0)
			(type default)
		)
	)
	(wire
		(pts
			(xy 325.12 78.74) (xy 337.82 78.74)
		)
		(stroke
			(width 0)
			(type default)
		)
	)
	(wire
		(pts
			(xy 200.66 64.77) (xy 220.98 64.77)
		)
		(stroke
			(width 0)
			(type default)
		)
	)
	(wire
		(pts
			(xy 322.58 104.14) (xy 322.58 105.41)
		)
		(stroke
			(width 0)
			(type default)
		)
	)
	(wire
		(pts
			(xy 38.1 196.85) (xy 50.8 196.85)
		)
		(stroke
			(width 0)
			(type default)
		)
	)
	(wire
		(pts
			(xy 270.51 154.94) (xy 270.51 156.21)
		)
		(stroke
			(width 0)
			(type default)
		)
	)
	(wire
		(pts
			(xy 342.9 222.25) (xy 344.17 222.25)
		)
		(stroke
			(width 0)
			(type default)
		)
	)
	(wire
		(pts
			(xy 40.64 210.82) (xy 40.64 214.63)
		)
		(stroke
			(width 0)
			(type default)
		)
	)
	(wire
		(pts
			(xy 40.64 214.63) (xy 38.1 214.63)
		)
		(stroke
			(width 0)
			(type default)
		)
	)
	(wire
		(pts
			(xy 325.12 223.52) (xy 325.12 224.79)
		)
		(stroke
			(width 0)
			(type default)
		)
	)
	(wire
		(pts
			(xy 160.02 138.43) (xy 157.48 138.43)
		)
		(stroke
			(width 0)
			(type default)
		)
	)
	(wire
		(pts
			(xy 317.5 133.35) (xy 317.5 132.08)
		)
		(stroke
			(width 0)
			(type default)
		)
	)
	(wire
		(pts
			(xy 179.07 260.35) (xy 194.31 260.35)
		)
		(stroke
			(width 0)
			(type default)
		)
	)
	(wire
		(pts
			(xy 208.28 184.15) (xy 208.28 186.69)
		)
		(stroke
			(width 0)
			(type default)
		)
	)
	(wire
		(pts
			(xy 95.25 58.42) (xy 111.76 58.42)
		)
		(stroke
			(width 0.5)
			(type default)
		)
	)
	(wire
		(pts
			(xy 92.71 66.04) (xy 95.25 66.04)
		)
		(stroke
			(width 0)
			(type default)
		)
	)
	(wire
		(pts
			(xy 151.13 196.85) (xy 151.13 184.15)
		)
		(stroke
			(width 0)
			(type default)
		)
	)
	(bus
		(pts
			(xy 71.12 74.93) (xy 71.12 80.01)
		)
		(stroke
			(width 0)
			(type default)
		)
	)
	(wire
		(pts
			(xy 187.96 123.19) (xy 198.12 123.19)
		)
		(stroke
			(width 0)
			(type default)
		)
	)
	(wire
		(pts
			(xy 111.76 35.56) (xy 111.76 58.42)
		)
		(stroke
			(width 0)
			(type default)
		)
	)
	(wire
		(pts
			(xy 200.66 182.88) (xy 200.66 184.15)
		)
		(stroke
			(width 0)
			(type default)
		)
	)
	(bus
		(pts
			(xy 384.81 90.17) (xy 384.81 92.71)
		)
		(stroke
			(width 0)
			(type default)
		)
	)
	(wire
		(pts
			(xy 243.84 60.96) (xy 243.84 64.77)
		)
		(stroke
			(width 0)
			(type default)
		)
	)
	(bus
		(pts
			(xy 322.58 74.93) (xy 322.58 91.44)
		)
		(stroke
			(width 0)
			(type default)
		)
	)
	(wire
		(pts
			(xy 293.37 54.61) (xy 337.82 54.61)
		)
		(stroke
			(width 0)
			(type default)
		)
	)
	(wire
		(pts
			(xy 274.32 36.83) (xy 274.32 39.37)
		)
		(stroke
			(width 0)
			(type default)
		)
	)
	(wire
		(pts
			(xy 111.76 66.04) (xy 120.65 66.04)
		)
		(stroke
			(width 0)
			(type default)
		)
	)
	(wire
		(pts
			(xy 40.64 72.39) (xy 40.64 76.2)
		)
		(stroke
			(width 0)
			(type default)
		)
	)
	(wire
		(pts
			(xy 262.89 154.94) (xy 262.89 156.21)
		)
		(stroke
			(width 0)
			(type default)
		)
	)
	(wire
		(pts
			(xy 176.53 140.97) (xy 177.8 140.97)
		)
		(stroke
			(width 0)
			(type default)
		)
	)
	(wire
		(pts
			(xy 369.57 140.97) (xy 370.84 140.97)
		)
		(stroke
			(width 0)
			(type default)
		)
	)
	(bus
		(pts
			(xy 381 227.33) (xy 379.73 227.33)
		)
		(stroke
			(width 0)
			(type default)
		)
	)
	(wire
		(pts
			(xy 77.47 58.42) (xy 77.47 59.69)
		)
		(stroke
			(width 0)
			(type default)
		)
	)
	(wire
		(pts
			(xy 293.37 154.94) (xy 293.37 156.21)
		)
		(stroke
			(width 0)
			(type default)
		)
	)
	(wire
		(pts
			(xy 369.57 151.13) (xy 370.84 151.13)
		)
		(stroke
			(width 0)
			(type default)
		)
	)
	(wire
		(pts
			(xy 92.71 80.01) (xy 92.71 81.28)
		)
		(stroke
			(width 0)
			(type default)
		)
	)
	(wire
		(pts
			(xy 92.71 80.01) (xy 95.25 80.01)
		)
		(stroke
			(width 0)
			(type default)
		)
	)
	(wire
		(pts
			(xy 39.37 232.41) (xy 39.37 236.22)
		)
		(stroke
			(width 0)
			(type default)
		)
	)
	(bus
		(pts
			(xy 71.12 91.44) (xy 322.58 91.44)
		)
		(stroke
			(width 0)
			(type default)
		)
	)
	(wire
		(pts
			(xy 270.51 149.86) (xy 270.51 146.05)
		)
		(stroke
			(width 0)
			(type default)
		)
	)
	(bus
		(pts
			(xy 71.12 224.79) (xy 80.01 224.79)
		)
		(stroke
			(width 0)
			(type default)
		)
	)
	(wire
		(pts
			(xy 368.3 222.25) (xy 368.3 223.52)
		)
		(stroke
			(width 0)
			(type default)
		)
	)
	(wire
		(pts
			(xy 365.76 222.25) (xy 365.76 227.33)
		)
		(stroke
			(width 0)
			(type default)
		)
	)
	(wire
		(pts
			(xy 313.69 180.34) (xy 313.69 240.03)
		)
		(stroke
			(width 0)
			(type default)
		)
	)
	(wire
		(pts
			(xy 194.31 184.15) (xy 198.12 184.15)
		)
		(stroke
			(width 0)
			(type default)
		)
	)
	(wire
		(pts
			(xy 77.47 66.04) (xy 77.47 64.77)
		)
		(stroke
			(width 0)
			(type default)
		)
	)
	(wire
		(pts
			(xy 66.04 41.91) (xy 67.31 41.91)
		)
		(stroke
			(width 0)
			(type default)
		)
	)
	(wire
		(pts
			(xy 160.02 257.81) (xy 161.29 257.81)
		)
		(stroke
			(width 0)
			(type default)
		)
	)
	(wire
		(pts
			(xy 262.89 22.86) (xy 262.89 36.83)
		)
		(stroke
			(width 0)
			(type default)
		)
	)
	(wire
		(pts
			(xy 234.95 54.61) (xy 243.84 54.61)
		)
		(stroke
			(width 0)
			(type default)
		)
	)
	(wire
		(pts
			(xy 38.1 63.5) (xy 48.26 63.5)
		)
		(stroke
			(width 0)
			(type default)
		)
	)
	(wire
		(pts
			(xy 274.32 36.83) (xy 281.94 36.83)
		)
		(stroke
			(width 0)
			(type default)
		)
	)
	(wire
		(pts
			(xy 364.49 185.42) (xy 370.84 185.42)
		)
		(stroke
			(width 0)
			(type default)
		)
	)
	(wire
		(pts
			(xy 167.64 184.15) (xy 167.64 195.58)
		)
		(stroke
			(width 0)
			(type default)
		)
	)
	(wire
		(pts
			(xy 151.13 196.85) (xy 149.86 196.85)
		)
		(stroke
			(width 0)
			(type default)
		)
	)
	(wire
		(pts
			(xy 369.57 116.84) (xy 382.27 116.84)
		)
		(stroke
			(width 0)
			(type default)
		)
	)
	(wire
		(pts
			(xy 336.55 90.17) (xy 337.82 90.17)
		)
		(stroke
			(width 0)
			(type default)
		)
	)
	(wire
		(pts
			(xy 313.69 240.03) (xy 318.77 240.03)
		)
		(stroke
			(width 0)
			(type default)
		)
	)
	(wire
		(pts
			(xy 208.28 191.77) (xy 208.28 194.31)
		)
		(stroke
			(width 0)
			(type default)
		)
	)
	(wire
		(pts
			(xy 119.38 259.08) (xy 129.54 259.08)
		)
		(stroke
			(width 0)
			(type default)
		)
	)
	(wire
		(pts
			(xy 317.5 104.14) (xy 317.5 105.41)
		)
		(stroke
			(width 0)
			(type default)
		)
	)
	(wire
		(pts
			(xy 43.18 77.47) (xy 43.18 78.74)
		)
		(stroke
			(width 0)
			(type default)
		)
	)
	(wire
		(pts
			(xy 306.07 49.53) (xy 337.82 49.53)
		)
		(stroke
			(width 0)
			(type default)
		)
	)
	(wire
		(pts
			(xy 332.74 118.11) (xy 335.28 118.11)
		)
		(stroke
			(width 0)
			(type default)
		)
	)
	(wire
		(pts
			(xy 66.04 41.91) (xy 66.04 44.45)
		)
		(stroke
			(width 0)
			(type default)
		)
	)
	(bus
		(pts
			(xy 384.81 87.63) (xy 384.81 90.17)
		)
		(stroke
			(width 0)
			(type default)
		)
	)
	(label "I2C_EN"
		(at 378.46 83.82 180)
		(effects
			(font
				(size 1.27 1.27)
			)
			(justify right bottom)
		)
	)
	(label "AD_N"
		(at 54.61 240.03 0)
		(effects
			(font
				(size 1.27 1.27)
			)
			(justify left bottom)
		)
	)
	(label "USBD_CC1"
		(at 48.26 63.5 180)
		(effects
			(font
				(size 1.27 1.27)
			)
			(justify right bottom)
		)
	)
	(label "I_{2}C1.SCL"
		(at 392.43 182.88 180)
		(effects
			(font
				(size 1.27 1.27)
			)
			(justify right bottom)
		)
	)
	(label "UART.0.TX"
		(at 382.27 52.07 180)
		(effects
			(font
				(size 1.27 1.27)
			)
			(justify right bottom)
		)
	)
	(label "BDBUS1"
		(at 336.55 185.42 0)
		(effects
			(font
				(size 1.27 1.27)
			)
			(justify left bottom)
		)
	)
	(label "BDBUS2"
		(at 378.46 76.2 180)
		(effects
			(font
				(size 1.27 1.27)
			)
			(justify right bottom)
		)
	)
	(label "+5V_{CAP}"
		(at 186.69 184.15 0)
		(effects
			(font
				(size 1.27 1.27)
			)
			(justify left bottom)
		)
	)
	(label "USB_3V3"
		(at 335.28 177.8 0)
		(effects
			(font
				(size 1.27 1.27)
			)
			(justify left bottom)
		)
	)
	(label "USBD_VBUS"
		(at 38.1 58.42 0)
		(effects
			(font
				(size 1.27 1.27)
			)
			(justify left bottom)
		)
	)
	(label "EECLK"
		(at 208.28 135.89 180)
		(effects
			(font
				(size 1.27 1.27)
			)
			(justify right bottom)
		)
	)
	(label "+5V_{CAP}"
		(at 168.91 241.3 180)
		(effects
			(font
				(size 1.27 1.27)
			)
			(justify right bottom)
		)
	)
	(label "EN_FTDI"
		(at 172.72 59.69 0)
		(effects
			(font
				(size 1.27 1.27)
			)
			(justify left bottom)
		)
	)
	(label "I2C_EN"
		(at 313.69 163.83 0)
		(effects
			(font
				(size 1.27 1.27)
			)
			(justify left bottom)
		)
	)
	(label "USB_3V3"
		(at 372.11 161.29 0)
		(effects
			(font
				(size 1.27 1.27)
			)
			(justify left bottom)
		)
	)
	(label "OUT_FTDI"
		(at 222.25 54.61 0)
		(effects
			(font
				(size 1.27 1.27)
			)
			(justify left bottom)
		)
	)
	(label "USBA_CC2"
		(at 119.38 259.08 0)
		(effects
			(font
				(size 1.27 1.27)
			)
			(justify left bottom)
		)
	)
	(label "UART.2.TX"
		(at 382.27 95.25 180)
		(effects
			(font
				(size 1.27 1.27)
			)
			(justify right bottom)
		)
	)
	(label "SW_FTDI"
		(at 200.66 54.61 0)
		(effects
			(font
				(size 1.27 1.27)
			)
			(justify left bottom)
		)
	)
	(label "UART.1.RX"
		(at 377.19 237.49 180)
		(effects
			(font
				(size 1.27 1.27)
			)
			(justify right bottom)
		)
	)
	(label "BDBUS2"
		(at 336.55 187.96 0)
		(effects
			(font
				(size 1.27 1.27)
			)
			(justify left bottom)
		)
	)
	(label "USBD.D_P"
		(at 325.12 69.85 0)
		(effects
			(font
				(size 1.27 1.27)
			)
			(justify left bottom)
		)
	)
	(label "USB_1V2"
		(at 271.78 146.05 180)
		(effects
			(font
				(size 1.27 1.27)
			)
			(justify right bottom)
		)
	)
	(label "UART.3.RX"
		(at 382.27 114.3 180)
		(effects
			(font
				(size 1.27 1.27)
			)
			(justify right bottom)
		)
	)
	(label "USBD_CC2"
		(at 325.12 81.28 0)
		(effects
			(font
				(size 1.27 1.27)
			)
			(justify left bottom)
		)
	)
	(label "BDBUS1"
		(at 378.46 73.66 180)
		(effects
			(font
				(size 1.27 1.27)
			)
			(justify right bottom)
		)
	)
	(label "USBA_OUT_EN"
		(at 152.4 201.93 0)
		(effects
			(font
				(size 1.27 1.27)
			)
			(justify left bottom)
		)
	)
	(label "USBD.D_P"
		(at 59.69 72.39 0)
		(effects
			(font
				(size 1.27 1.27)
			)
			(justify left bottom)
		)
	)
	(label "USBD_SVBUS"
		(at 91.44 137.16 180)
		(effects
			(font
				(size 1.27 1.27)
			)
			(justify right bottom)
		)
	)
	(label "EECLK"
		(at 325.12 95.25 0)
		(effects
			(font
				(size 1.27 1.27)
			)
			(justify left bottom)
		)
	)
	(label "USBD.D_N"
		(at 325.12 72.39 0)
		(effects
			(font
				(size 1.27 1.27)
			)
			(justify left bottom)
		)
	)
	(label "USBA.OTGID"
		(at 182.88 260.35 0)
		(effects
			(font
				(size 1.27 1.27)
			)
			(justify left bottom)
		)
	)
	(label "DD_P"
		(at 57.15 36.83 0)
		(effects
			(font
				(size 1.27 1.27)
			)
			(justify left bottom)
		)
	)
	(label "BDBUS0"
		(at 336.55 182.88 0)
		(effects
			(font
				(size 1.27 1.27)
			)
			(justify left bottom)
		)
	)
	(label "AD_N"
		(at 44.45 215.9 0)
		(effects
			(font
				(size 1.27 1.27)
			)
			(justify left bottom)
		)
	)
	(label "USBA_CC1"
		(at 48.26 201.93 180)
		(effects
			(font
				(size 1.27 1.27)
			)
			(justify right bottom)
		)
	)
	(label "USBD_CC1"
		(at 325.12 78.74 0)
		(effects
			(font
				(size 1.27 1.27)
			)
			(justify left bottom)
		)
	)
	(label "USB_3V3"
		(at 328.93 171.45 180)
		(effects
			(font
				(size 1.27 1.27)
			)
			(justify right bottom)
		)
	)
	(label "UART.2.RX"
		(at 382.27 92.71 180)
		(effects
			(font
				(size 1.27 1.27)
			)
			(justify right bottom)
		)
	)
	(label "USBA.D_P"
		(at 59.69 210.82 0)
		(effects
			(font
				(size 1.27 1.27)
			)
			(justify left bottom)
		)
	)
	(label "USBD{USB}"
		(at 72.39 91.44 0)
		(effects
			(font
				(size 1.27 1.27)
			)
			(justify left bottom)
		)
	)
	(label "USBA_CC1"
		(at 119.38 256.54 0)
		(effects
			(font
				(size 1.27 1.27)
			)
			(justify left bottom)
		)
	)
	(label "USBA_CC2"
		(at 48.26 204.47 180)
		(effects
			(font
				(size 1.27 1.27)
			)
			(justify right bottom)
		)
	)
	(label "USB_3V3"
		(at 325.12 223.52 180)
		(effects
			(font
				(size 1.27 1.27)
			)
			(justify right bottom)
		)
	)
	(label "+5V_{CAP}"
		(at 121.92 241.3 0)
		(effects
			(font
				(size 1.27 1.27)
			)
			(justify left bottom)
		)
	)
	(label "USBD.D_N"
		(at 59.69 77.47 0)
		(effects
			(font
				(size 1.27 1.27)
			)
			(justify left bottom)
		)
	)
	(label "AD_P"
		(at 54.61 237.49 0)
		(effects
			(font
				(size 1.27 1.27)
			)
			(justify left bottom)
		)
	)
	(label "USB_3V3"
		(at 138.43 133.35 0)
		(effects
			(font
				(size 1.27 1.27)
			)
			(justify left bottom)
		)
	)
	(label "DD_N"
		(at 44.45 77.47 0)
		(effects
			(font
				(size 1.27 1.27)
			)
			(justify left bottom)
		)
	)
	(label "USB_3V3"
		(at 325.12 52.07 0)
		(effects
			(font
				(size 1.27 1.27)
			)
			(justify left bottom)
		)
	)
	(label "BDBUS1"
		(at 336.55 232.41 0)
		(effects
			(font
				(size 1.27 1.27)
			)
			(justify left bottom)
		)
	)
	(label "I_{2}C1.SDA"
		(at 392.43 185.42 180)
		(effects
			(font
				(size 1.27 1.27)
			)
			(justify right bottom)
		)
	)
	(label "USBD_SVBUS"
		(at 325.12 76.2 0)
		(effects
			(font
				(size 1.27 1.27)
			)
			(justify left bottom)
		)
	)
	(label "USBD_CC2"
		(at 48.26 66.04 180)
		(effects
			(font
				(size 1.27 1.27)
			)
			(justify right bottom)
		)
	)
	(label "EECS"
		(at 208.28 133.35 180)
		(effects
			(font
				(size 1.27 1.27)
			)
			(justify right bottom)
		)
	)
	(label "EECS"
		(at 325.12 100.33 0)
		(effects
			(font
				(size 1.27 1.27)
			)
			(justify left bottom)
		)
	)
	(label "USBA_CC1"
		(at 54.61 232.41 0)
		(effects
			(font
				(size 1.27 1.27)
			)
			(justify left bottom)
		)
	)
	(label "EEDATA"
		(at 208.28 138.43 180)
		(effects
			(font
				(size 1.27 1.27)
			)
			(justify right bottom)
		)
	)
	(label "DD_P"
		(at 44.45 72.39 0)
		(effects
			(font
				(size 1.27 1.27)
			)
			(justify left bottom)
		)
	)
	(label "VREGIN"
		(at 325.12 49.53 0)
		(effects
			(font
				(size 1.27 1.27)
			)
			(justify left bottom)
		)
	)
	(label "USBD_IN_EN"
		(at 140.97 74.93 180)
		(effects
			(font
				(size 1.27 1.27)
			)
			(justify right bottom)
		)
	)
	(label "USBD_CC1"
		(at 57.15 31.75 0)
		(effects
			(font
				(size 1.27 1.27)
			)
			(justify left bottom)
		)
	)
	(label "VCC_USB"
		(at 325.12 54.61 0)
		(effects
			(font
				(size 1.27 1.27)
			)
			(justify left bottom)
		)
	)
	(label "FB_FTDI"
		(at 210.82 64.77 0)
		(effects
			(font
				(size 1.27 1.27)
			)
			(justify left bottom)
		)
	)
	(label "DD_N"
		(at 57.15 39.37 0)
		(effects
			(font
				(size 1.27 1.27)
			)
			(justify left bottom)
		)
	)
	(label "USB_3V3"
		(at 335.28 217.17 0)
		(effects
			(font
				(size 1.27 1.27)
			)
			(justify left bottom)
		)
	)
	(label "UART.3.TX"
		(at 382.27 116.84 180)
		(effects
			(font
				(size 1.27 1.27)
			)
			(justify right bottom)
		)
	)
	(label "USB_3V3"
		(at 208.28 123.19 180)
		(effects
			(font
				(size 1.27 1.27)
			)
			(justify right bottom)
		)
	)
	(label "USB_3V3"
		(at 317.5 102.87 180)
		(effects
			(font
				(size 1.27 1.27)
			)
			(justify right bottom)
		)
	)
	(label "BDBUS0"
		(at 336.55 237.49 0)
		(effects
			(font
				(size 1.27 1.27)
			)
			(justify left bottom)
		)
	)
	(label "AD_P"
		(at 44.45 210.82 0)
		(effects
			(font
				(size 1.27 1.27)
			)
			(justify left bottom)
		)
	)
	(label "USBD_IN_EN"
		(at 392.43 143.51 180)
		(effects
			(font
				(size 1.27 1.27)
			)
			(justify right bottom)
		)
	)
	(label "EEDATA"
		(at 325.12 97.79 0)
		(effects
			(font
				(size 1.27 1.27)
			)
			(justify left bottom)
		)
	)
	(label "UART.0.RX"
		(at 382.27 49.53 180)
		(effects
			(font
				(size 1.27 1.27)
			)
			(justify right bottom)
		)
	)
	(label "USB_3V3"
		(at 372.11 198.12 0)
		(effects
			(font
				(size 1.27 1.27)
			)
			(justify left bottom)
		)
	)
	(label "USBD_VBUS"
		(at 71.12 127 0)
		(effects
			(font
				(size 1.27 1.27)
			)
			(justify left bottom)
		)
	)
	(label "VCC_PD"
		(at 325.12 57.15 0)
		(effects
			(font
				(size 1.27 1.27)
			)
			(justify left bottom)
		)
	)
	(label "USBD_CC2"
		(at 57.15 34.29 0)
		(effects
			(font
				(size 1.27 1.27)
			)
			(justify left bottom)
		)
	)
	(label "UART.1.TX"
		(at 377.19 232.41 180)
		(effects
			(font
				(size 1.27 1.27)
			)
			(justify right bottom)
		)
	)
	(label "USBA.D_N"
		(at 59.69 215.9 0)
		(effects
			(font
				(size 1.27 1.27)
			)
			(justify left bottom)
		)
	)
	(label "USBA_CC2"
		(at 54.61 234.95 0)
		(effects
			(font
				(size 1.27 1.27)
			)
			(justify left bottom)
		)
	)
	(label "BDBUS0"
		(at 378.46 71.12 180)
		(effects
			(font
				(size 1.27 1.27)
			)
			(justify right bottom)
		)
	)
	(label "USBD{USB}"
		(at 322.58 91.44 180)
		(effects
			(font
				(size 1.27 1.27)
			)
			(justify right bottom)
		)
	)
	(hierarchical_label "UART.0{UART}"
		(shape bidirectional)
		(at 386.08 44.45 0)
		(effects
			(font
				(size 1.27 1.27)
			)
			(justify left)
		)
	)
	(hierarchical_label "UART.3{UART}"
		(shape bidirectional)
		(at 386.08 109.22 0)
		(effects
			(font
				(size 1.27 1.27)
			)
			(justify left)
		)
	)
	(hierarchical_label "UART.1{UART}"
		(shape bidirectional)
		(at 381 227.33 0)
		(effects
			(font
				(size 1.27 1.27)
			)
			(justify left)
		)
	)
	(hierarchical_label "V_{BUS}"
		(shape output)
		(at 134.62 58.42 0)
		(effects
			(font
				(size 1.27 1.27)
				(thickness 0.254)
				(bold yes)
			)
			(justify left)
		)
	)
	(hierarchical_label "USBA_VBUS"
		(shape output)
		(at 52.07 194.31 0)
		(effects
			(font
				(size 1.27 1.27)
			)
			(justify left)
		)
	)
	(hierarchical_label "USBA{USB}"
		(shape bidirectional)
		(at 80.01 224.79 0)
		(effects
			(font
				(size 1.27 1.27)
			)
			(justify left)
		)
	)
	(hierarchical_label "UART.2{UART}"
		(shape bidirectional)
		(at 386.08 87.63 0)
		(effects
			(font
				(size 1.27 1.27)
			)
			(justify left)
		)
	)
	(hierarchical_label "I_{2}C1{I_{2}C}"
		(shape bidirectional)
		(at 394.97 179.07 0)
		(effects
			(font
				(size 1.27 1.27)
			)
			(justify left)
		)
	)
	(hierarchical_label "USBA{USB}"
		(shape bidirectional)
		(at 198.12 257.81 0)
		(effects
			(font
				(size 1.27 1.27)
			)
			(justify left)
		)
	)
	(symbol
		(lib_id "antmicroTestPoints:TP_0.75mm_SMD")
		(at 77.47 135.89 90)
		(unit 1)
		(exclude_from_sim no)
		(in_bom no)
		(on_board yes)
		(dnp no)
		(fields_autoplaced yes)
		(property "Reference" "TP902"
			(at 79.375 132.7149 90)
			(effects
				(font
					(size 1.27 1.27)
				)
				(justify right)
			)
		)
		(property "Value" "TP_0.75mm_SMD"
			(at 80.01 135.89 0)
			(effects
				(font
					(size 1.27 1.27)
					(thickness 0.15)
				)
				(justify left bottom)
				(hide yes)
			)
		)
		(property "Footprint" "antmicro-footprints:TP_SMD_0.75mm"
			(at 72.39 130.81 0)
			(effects
				(font
					(size 1.27 1.27)
					(thickness 0.15)
				)
				(justify left bottom)
				(hide yes)
			)
		)
		(property "Datasheet" ""
			(at 69.85 130.81 0)
			(effects
				(font
					(size 1.27 1.27)
					(thickness 0.15)
				)
				(justify left bottom)
				(hide yes)
			)
		)
		(property "Description" ""
			(at 77.47 135.89 0)
			(effects
				(font
					(size 1.27 1.27)
				)
				(hide yes)
			)
		)
		(property "MPN" ""
			(at 77.47 135.89 0)
			(effects
				(font
					(size 1.27 1.27)
					(thickness 0.15)
				)
				(justify left bottom)
				(hide yes)
			)
		)
		(property "Manufacturer" ""
			(at 77.47 135.89 0)
			(effects
				(font
					(size 1.27 1.27)
					(thickness 0.15)
				)
				(justify left bottom)
				(hide yes)
			)
		)
		(property "Author" "Antmicro"
			(at 92.71 120.65 0)
			(effects
				(font
					(size 1.27 1.27)
					(thickness 0.15)
				)
				(justify left bottom)
				(hide yes)
			)
		)
		(property "License" "Apache-2.0"
			(at 95.25 120.65 0)
			(effects
				(font
					(size 1.27 1.27)
					(thickness 0.15)
				)
				(justify left bottom)
				(hide yes)
			)
		)
		(pin "1"
		)
		(instances
			(project "cm4-baseboard"
				(path ""
					(reference "TP902")
					(unit 1)
				)
			)
			(project "usb"
				(path ""
					(reference "TP902")
					(unit 1)
				)
			)
		)
	)
	(symbol
		(lib_id "antmicroResistors0402:R_200R_0402")
		(at 220.98 175.26 180)
		(unit 1)
		(exclude_from_sim no)
		(in_bom yes)
		(on_board yes)
		(dnp no)
		(fields_autoplaced yes)
		(property "Reference" "R926"
			(at 218.44 168.91 0)
			(effects
				(font
					(size 1.27 1.27)
					(thickness 0.15)
				)
			)
		)
		(property "Value" "R_200R_0402"
			(at 200.66 162.56 0)
			(effects
				(font
					(size 1.27 1.27)
					(thickness 0.15)
				)
				(justify left bottom)
				(hide yes)
			)
		)
		(property "Footprint" "antmicro-footprints:R_0402_1005Metric"
			(at 200.66 160.02 0)
			(effects
				(font
					(size 1.27 1.27)
					(thickness 0.15)
				)
				(justify left bottom)
				(hide yes)
			)
		)
		(property "Datasheet" "https://www.bourns.com/docs/product-datasheets/cr.pdf"
			(at 200.66 157.48 0)
			(effects
				(font
					(size 1.27 1.27)
					(thickness 0.15)
				)
				(justify left bottom)
				(hide yes)
			)
		)
		(property "Description" ""
			(at 220.98 175.26 0)
			(effects
				(font
					(size 1.27 1.27)
				)
				(hide yes)
			)
		)
		(property "MPN" "CR0402-FX-2000GLF"
			(at 200.66 154.94 0)
			(effects
				(font
					(size 1.27 1.27)
					(thickness 0.15)
				)
				(justify left bottom)
				(hide yes)
			)
		)
		(property "Manufacturer" "Bourns"
			(at 200.66 152.4 0)
			(effects
				(font
					(size 1.27 1.27)
					(thickness 0.15)
				)
				(justify left bottom)
				(hide yes)
			)
		)
		(property "License" "Apache-2.0"
			(at 200.66 149.86 0)
			(effects
				(font
					(size 1.27 1.27)
					(thickness 0.15)
				)
				(justify left bottom)
				(hide yes)
			)
		)
		(property "Author" "Antmicro"
			(at 200.66 147.32 0)
			(effects
				(font
					(size 1.27 1.27)
					(thickness 0.15)
				)
				(justify left bottom)
				(hide yes)
			)
		)
		(property "Val" "200R"
			(at 218.44 171.45 0)
			(effects
				(font
					(size 1.27 1.27)
					(thickness 0.15)
				)
			)
		)
		(property "Tolerance" "1%"
			(at 200.66 165.1 0)
			(effects
				(font
					(size 1.27 1.27)
				)
				(justify left bottom)
				(hide yes)
			)
		)
		(pin "1"
		)
		(pin "2"
		)
		(instances
			(project "cm4-baseboard"
				(path ""
					(reference "R926")
					(unit 1)
				)
			)
			(project "usb"
				(path ""
					(reference "R926")
					(unit 1)
				)
			)
		)
	)
	(symbol
		(lib_id "antmicroTestPoints:TP_0.75mm_SMD")
		(at 161.29 267.97 0)
		(mirror x)
		(unit 1)
		(exclude_from_sim no)
		(in_bom no)
		(on_board yes)
		(dnp no)
		(property "Reference" "TP912"
			(at 165.1 267.97 0)
			(effects
				(font
					(size 1.27 1.27)
				)
				(justify left)
			)
		)
		(property "Value" "TP_0.75mm_SMD"
			(at 161.29 265.43 0)
			(effects
				(font
					(size 1.27 1.27)
					(thickness 0.15)
				)
				(justify left bottom)
				(hide yes)
			)
		)
		(property "Footprint" "antmicro-footprints:TP_SMD_0.75mm"
			(at 166.37 273.05 0)
			(effects
				(font
					(size 1.27 1.27)
					(thickness 0.15)
				)
				(justify left bottom)
				(hide yes)
			)
		)
		(property "Datasheet" ""
			(at 166.37 275.59 0)
			(effects
				(font
					(size 1.27 1.27)
					(thickness 0.15)
				)
				(justify left bottom)
				(hide yes)
			)
		)
		(property "Description" ""
			(at 161.29 267.97 0)
			(effects
				(font
					(size 1.27 1.27)
				)
				(hide yes)
			)
		)
		(property "MPN" ""
			(at 161.29 267.97 0)
			(effects
				(font
					(size 1.27 1.27)
					(thickness 0.15)
				)
				(justify left bottom)
				(hide yes)
			)
		)
		(property "Manufacturer" ""
			(at 161.29 267.97 0)
			(effects
				(font
					(size 1.27 1.27)
					(thickness 0.15)
				)
				(justify left bottom)
				(hide yes)
			)
		)
		(property "Author" "Antmicro"
			(at 176.53 252.73 0)
			(effects
				(font
					(size 1.27 1.27)
					(thickness 0.15)
				)
				(justify left bottom)
				(hide yes)
			)
		)
		(property "License" "Apache-2.0"
			(at 176.53 250.19 0)
			(effects
				(font
					(size 1.27 1.27)
					(thickness 0.15)
				)
				(justify left bottom)
				(hide yes)
			)
		)
		(pin "1"
		)
		(instances
			(project "cm4-baseboard"
				(path ""
					(reference "TP912")
					(unit 1)
				)
			)
			(project "usb"
				(path ""
					(reference "TP912")
					(unit 1)
				)
			)
		)
	)
	(symbol
		(lib_id "antmicroResistors0402:R_10k_0402")
		(at 172.72 245.11 270)
		(unit 1)
		(exclude_from_sim no)
		(in_bom yes)
		(on_board yes)
		(dnp no)
		(property "Reference" "R924"
			(at 173.99 245.11 90)
			(effects
				(font
					(size 1.27 1.27)
				)
				(justify left)
			)
		)
		(property "Value" "R_10k_0402"
			(at 160.02 265.43 0)
			(effects
				(font
					(size 1.27 1.27)
					(thickness 0.15)
				)
				(justify left bottom)
				(hide yes)
			)
		)
		(property "Footprint" "antmicro-footprints:R_0402_1005Metric"
			(at 157.48 265.43 0)
			(effects
				(font
					(size 1.27 1.27)
					(thickness 0.15)
				)
				(justify left bottom)
				(hide yes)
			)
		)
		(property "Datasheet" "https://www.bourns.com/docs/product-datasheets/cr.pdf"
			(at 154.94 265.43 0)
			(effects
				(font
					(size 1.27 1.27)
					(thickness 0.15)
				)
				(justify left bottom)
				(hide yes)
			)
		)
		(property "Description" ""
			(at 172.72 245.11 0)
			(effects
				(font
					(size 1.27 1.27)
				)
				(hide yes)
			)
		)
		(property "Manufacturer" "Bourns"
			(at 149.86 265.43 0)
			(effects
				(font
					(size 1.27 1.27)
					(thickness 0.15)
				)
				(justify left bottom)
				(hide yes)
			)
		)
		(property "MPN" "CR0402-FX-1002GLF"
			(at 152.4 265.43 0)
			(effects
				(font
					(size 1.27 1.27)
					(thickness 0.15)
				)
				(justify left bottom)
				(hide yes)
			)
		)
		(property "Val" "10k"
			(at 173.99 247.65 90)
			(effects
				(font
					(size 1.27 1.27)
					(thickness 0.15)
				)
				(justify left)
			)
		)
		(property "License" "Apache-2.0"
			(at 147.32 265.43 0)
			(effects
				(font
					(size 1.27 1.27)
					(thickness 0.15)
				)
				(justify left bottom)
				(hide yes)
			)
		)
		(property "Author" "Antmicro"
			(at 144.78 265.43 0)
			(effects
				(font
					(size 1.27 1.27)
					(thickness 0.15)
				)
				(justify left bottom)
				(hide yes)
			)
		)
		(property "Tolerance" "1%"
			(at 162.56 265.43 0)
			(effects
				(font
					(size 1.27 1.27)
				)
				(justify left bottom)
				(hide yes)
			)
		)
		(pin "1"
		)
		(pin "2"
		)
		(instances
			(project "cm4-baseboard"
				(path ""
					(reference "R924")
					(unit 1)
				)
			)
			(project "usb"
				(path ""
					(reference "R924")
					(unit 1)
				)
			)
		)
	)
	(symbol
		(lib_id "antmicroCapacitors0402:C_100n_0402")
		(at 274.32 39.37 270)
		(unit 1)
		(exclude_from_sim no)
		(in_bom yes)
		(on_board yes)
		(dnp no)
		(property "Reference" "C915"
			(at 274.955 40.0177 90)
			(effects
				(font
					(size 1.27 1.27)
				)
				(justify left)
			)
		)
		(property "Value" "C_100n_0402"
			(at 270.51 39.37 0)
			(effects
				(font
					(size 1.27 1.27)
					(thickness 0.15)
				)
				(justify left bottom)
				(hide yes)
			)
		)
		(property "Footprint" "antmicro-footprints:C_0402_1005Metric"
			(at 279.4 44.45 0)
			(effects
				(font
					(size 1.27 1.27)
					(thickness 0.15)
				)
				(justify left bottom)
				(hide yes)
			)
		)
		(property "Datasheet" "https://www.murata.com/products/productdetail?partno=GRM155R61H104KE14%23"
			(at 274.32 39.37 0)
			(effects
				(font
					(size 1.27 1.27)
					(thickness 0.15)
				)
				(justify left bottom)
				(hide yes)
			)
		)
		(property "Description" ""
			(at 274.32 39.37 0)
			(effects
				(font
					(size 1.27 1.27)
				)
				(hide yes)
			)
		)
		(property "Manufacturer" "Murata"
			(at 284.48 44.45 0)
			(effects
				(font
					(size 1.27 1.27)
					(thickness 0.15)
				)
				(justify left bottom)
				(hide yes)
			)
		)
		(property "MPN" "GRM155R61H104KE14D"
			(at 281.94 44.45 0)
			(effects
				(font
					(size 1.27 1.27)
					(thickness 0.15)
				)
				(justify left bottom)
				(hide yes)
			)
		)
		(property "Val" "100n"
			(at 274.955 43.8277 90)
			(effects
				(font
					(size 1.27 1.27)
					(thickness 0.15)
				)
				(justify left)
			)
		)
		(property "License" "Apache-2.0"
			(at 251.46 59.69 0)
			(effects
				(font
					(size 1.27 1.27)
					(thickness 0.15)
				)
				(justify left bottom)
				(hide yes)
			)
		)
		(property "Author" "Antmicro"
			(at 248.92 59.69 0)
			(effects
				(font
					(size 1.27 1.27)
					(thickness 0.15)
				)
				(justify left bottom)
				(hide yes)
			)
		)
		(property "Voltage" "50V"
			(at 246.38 59.69 0)
			(effects
				(font
					(size 1.27 1.27)
				)
				(justify left bottom)
				(hide yes)
			)
		)
		(property "Dielectric" "X5R"
			(at 243.84 59.69 0)
			(effects
				(font
					(size 1.27 1.27)
				)
				(justify left bottom)
				(hide yes)
			)
		)
		(pin "1"
		)
		(pin "2"
		)
		(instances
			(project "cm4-baseboard"
				(path ""
					(reference "C915")
					(unit 1)
				)
			)
			(project "usb"
				(path ""
					(reference "C915")
					(unit 1)
				)
			)
		)
	)
	(symbol
		(lib_id "antmicropower:GND")
		(at 157.48 142.24 0)
		(unit 1)
		(exclude_from_sim no)
		(in_bom yes)
		(on_board yes)
		(dnp no)
		(fields_autoplaced yes)
		(property "Reference" "#PWR0915"
			(at 157.48 148.59 0)
			(effects
				(font
					(size 1.27 1.27)
				)
				(hide yes)
			)
		)
		(property "Value" "GND"
			(at 157.48 147.32 0)
			(effects
				(font
					(size 1.27 1.27)
				)
			)
		)
		(property "Footprint" ""
			(at 166.37 149.86 0)
			(effects
				(font
					(size 1.27 1.27)
					(thickness 0.15)
				)
				(justify left bottom)
				(hide yes)
			)
		)
		(property "Datasheet" ""
			(at 166.37 154.94 0)
			(effects
				(font
					(size 1.27 1.27)
					(thickness 0.15)
				)
				(justify left bottom)
				(hide yes)
			)
		)
		(property "Description" ""
			(at 157.48 142.24 0)
			(effects
				(font
					(size 1.27 1.27)
				)
				(hide yes)
			)
		)
		(property "Author" "Antmicro"
			(at 166.37 149.86 0)
			(effects
				(font
					(size 1.27 1.27)
					(thickness 0.15)
				)
				(justify left bottom)
				(hide yes)
			)
		)
		(property "License" "Apache-2.0"
			(at 166.37 152.4 0)
			(effects
				(font
					(size 1.27 1.27)
					(thickness 0.15)
				)
				(justify left bottom)
				(hide yes)
			)
		)
		(pin "1"
		)
		(instances
			(project "cm4-baseboard"
				(path ""
					(reference "#PWR0915")
					(unit 1)
				)
			)
			(project "usb"
				(path ""
					(reference "#PWR0915")
					(unit 1)
				)
			)
		)
	)
	(symbol
		(lib_id "antmicropower:GND")
		(at 243.84 72.39 0)
		(mirror y)
		(unit 1)
		(exclude_from_sim no)
		(in_bom yes)
		(on_board yes)
		(dnp no)
		(fields_autoplaced yes)
		(property "Reference" "#PWR0928"
			(at 234.95 74.93 0)
			(effects
				(font
					(size 1.27 1.27)
					(thickness 0.15)
				)
				(justify left bottom)
				(hide yes)
			)
		)
		(property "Value" "GND"
			(at 245.8502 77.47 0)
			(effects
				(font
					(size 1.27 1.27)
					(thickness 0.15)
				)
				(justify left bottom)
			)
		)
		(property "Footprint" ""
			(at 234.95 80.01 0)
			(effects
				(font
					(size 1.27 1.27)
					(thickness 0.15)
				)
				(justify left bottom)
				(hide yes)
			)
		)
		(property "Datasheet" ""
			(at 234.95 85.09 0)
			(effects
				(font
					(size 1.27 1.27)
					(thickness 0.15)
				)
				(justify left bottom)
				(hide yes)
			)
		)
		(property "Description" ""
			(at 243.84 72.39 0)
			(effects
				(font
					(size 1.27 1.27)
				)
				(hide yes)
			)
		)
		(property "Author" "Antmicro"
			(at 234.95 80.01 0)
			(effects
				(font
					(size 1.27 1.27)
					(thickness 0.15)
				)
				(justify left bottom)
				(hide yes)
			)
		)
		(property "License" "Apache-2.0"
			(at 234.95 82.55 0)
			(effects
				(font
					(size 1.27 1.27)
					(thickness 0.15)
				)
				(justify left bottom)
				(hide yes)
			)
		)
		(pin "1"
		)
		(instances
			(project "cm4-baseboard"
				(path ""
					(reference "#PWR0928")
					(unit 1)
				)
			)
			(project "usb"
				(path ""
					(reference "#PWR0928")
					(unit 1)
				)
			)
		)
	)
	(symbol
		(lib_id "antmicropower:GND")
		(at 331.47 156.21 0)
		(unit 1)
		(exclude_from_sim no)
		(in_bom yes)
		(on_board yes)
		(dnp no)
		(fields_autoplaced yes)
		(property "Reference" "#PWR0952"
			(at 340.36 158.75 0)
			(effects
				(font
					(size 1.27 1.27)
					(thickness 0.15)
				)
				(justify left bottom)
				(hide yes)
			)
		)
		(property "Value" "GND"
			(at 331.47 161.29 0)
			(effects
				(font
					(size 1.27 1.27)
					(thickness 0.15)
				)
			)
		)
		(property "Footprint" ""
			(at 340.36 163.83 0)
			(effects
				(font
					(size 1.27 1.27)
					(thickness 0.15)
				)
				(justify left bottom)
				(hide yes)
			)
		)
		(property "Datasheet" ""
			(at 340.36 168.91 0)
			(effects
				(font
					(size 1.27 1.27)
					(thickness 0.15)
				)
				(justify left bottom)
				(hide yes)
			)
		)
		(property "Description" ""
			(at 331.47 156.21 0)
			(effects
				(font
					(size 1.27 1.27)
				)
				(hide yes)
			)
		)
		(property "Author" "Antmicro"
			(at 340.36 163.83 0)
			(effects
				(font
					(size 1.27 1.27)
					(thickness 0.15)
				)
				(justify left bottom)
				(hide yes)
			)
		)
		(property "License" "Apache-2.0"
			(at 340.36 166.37 0)
			(effects
				(font
					(size 1.27 1.27)
					(thickness 0.15)
				)
				(justify left bottom)
				(hide yes)
			)
		)
		(pin "1"
		)
		(instances
			(project "cm4-baseboard"
				(path ""
					(reference "#PWR0952")
					(unit 1)
				)
			)
			(project "usb"
				(path ""
					(reference "#PWR0952")
					(unit 1)
				)
			)
		)
	)
	(symbol
		(lib_id "antmicroCapacitors0402:C_100n_0402")
		(at 208.28 59.69 180)
		(unit 1)
		(exclude_from_sim no)
		(in_bom yes)
		(on_board yes)
		(dnp no)
		(property "Reference" "C906"
			(at 205.74 57.15 0)
			(effects
				(font
					(size 1.27 1.27)
					(thickness 0.15)
				)
			)
		)
		(property "Value" "C_100n_0402"
			(at 187.96 49.53 0)
			(effects
				(font
					(size 1.27 1.27)
					(thickness 0.15)
				)
				(justify left bottom)
				(hide yes)
			)
		)
		(property "Footprint" "antmicro-footprints:C_0402_1005Metric"
			(at 187.96 46.99 0)
			(effects
				(font
					(size 1.27 1.27)
					(thickness 0.15)
				)
				(justify left bottom)
				(hide yes)
			)
		)
		(property "Datasheet" "https://www.murata.com/products/productdetail?partno=GRM155R61H104KE14%23"
			(at 187.96 44.45 0)
			(effects
				(font
					(size 1.27 1.27)
					(thickness 0.15)
				)
				(justify left bottom)
				(hide yes)
			)
		)
		(property "Description" ""
			(at 208.28 59.69 0)
			(effects
				(font
					(size 1.27 1.27)
				)
				(hide yes)
			)
		)
		(property "Manufacturer" "Murata"
			(at 187.96 39.37 0)
			(effects
				(font
					(size 1.27 1.27)
					(thickness 0.15)
				)
				(justify left bottom)
				(hide yes)
			)
		)
		(property "MPN" "GRM155R61H104KE14D"
			(at 187.96 41.91 0)
			(effects
				(font
					(size 1.27 1.27)
					(thickness 0.15)
				)
				(justify left bottom)
				(hide yes)
			)
		)
		(property "Val" "100n"
			(at 205.74 62.23 0)
			(effects
				(font
					(size 1.27 1.27)
					(thickness 0.15)
				)
			)
		)
		(property "License" "Apache-2.0"
			(at 187.96 36.83 0)
			(effects
				(font
					(size 1.27 1.27)
					(thickness 0.15)
				)
				(justify left bottom)
				(hide yes)
			)
		)
		(property "Author" "Antmicro"
			(at 187.96 34.29 0)
			(effects
				(font
					(size 1.27 1.27)
					(thickness 0.15)
				)
				(justify left bottom)
				(hide yes)
			)
		)
		(property "Voltage" "50V"
			(at 187.96 31.75 0)
			(effects
				(font
					(size 1.27 1.27)
				)
				(justify left bottom)
				(hide yes)
			)
		)
		(property "Dielectric" "X5R"
			(at 187.96 29.21 0)
			(effects
				(font
					(size 1.27 1.27)
				)
				(justify left bottom)
				(hide yes)
			)
		)
		(pin "1"
		)
		(pin "2"
		)
		(instances
			(project "cm4-baseboard"
				(path ""
					(reference "C906")
					(unit 1)
				)
			)
			(project "usb"
				(path ""
					(reference "C906")
					(unit 1)
				)
			)
		)
	)
	(symbol
		(lib_id "antmicropower:GND")
		(at 313.69 247.65 0)
		(unit 1)
		(exclude_from_sim no)
		(in_bom yes)
		(on_board yes)
		(dnp no)
		(property "Reference" "#PWR05"
			(at 322.58 250.19 0)
			(effects
				(font
					(size 1.27 1.27)
					(thickness 0.15)
				)
				(justify left bottom)
				(hide yes)
			)
		)
		(property "Value" "GND"
			(at 313.69 251.46 0)
			(effects
				(font
					(size 1.27 1.27)
					(thickness 0.15)
				)
			)
		)
		(property "Footprint" ""
			(at 322.58 255.27 0)
			(effects
				(font
					(size 1.27 1.27)
					(thickness 0.15)
				)
				(justify left bottom)
				(hide yes)
			)
		)
		(property "Datasheet" ""
			(at 322.58 260.35 0)
			(effects
				(font
					(size 1.27 1.27)
					(thickness 0.15)
				)
				(justify left bottom)
				(hide yes)
			)
		)
		(property "Description" ""
			(at 313.69 247.65 0)
			(effects
				(font
					(size 1.27 1.27)
				)
				(hide yes)
			)
		)
		(property "Author" "Antmicro"
			(at 322.58 255.27 0)
			(effects
				(font
					(size 1.27 1.27)
					(thickness 0.15)
				)
				(justify left bottom)
				(hide yes)
			)
		)
		(property "License" "Apache-2.0"
			(at 322.58 257.81 0)
			(effects
				(font
					(size 1.27 1.27)
					(thickness 0.15)
				)
				(justify left bottom)
				(hide yes)
			)
		)
		(pin "1"
		)
		(instances
			(project "cm4-baseboard"
				(path ""
					(reference "#PWR05")
					(unit 1)
				)
			)
		)
	)
	(symbol
		(lib_id "antmicroTestPoints:TP_0.75mm_SMD")
		(at 336.55 90.17 180)
		(unit 1)
		(exclude_from_sim no)
		(in_bom no)
		(on_board yes)
		(dnp no)
		(fields_autoplaced yes)
		(property "Reference" "TP915"
			(at 331.47 90.17 0)
			(effects
				(font
					(size 1.27 1.27)
				)
				(justify left)
			)
		)
		(property "Value" "TP_0.75mm_SMD"
			(at 336.55 87.63 0)
			(effects
				(font
					(size 1.27 1.27)
					(thickness 0.15)
				)
				(justify left bottom)
				(hide yes)
			)
		)
		(property "Footprint" "antmicro-footprints:TP_SMD_0.75mm"
			(at 331.47 95.25 0)
			(effects
				(font
					(size 1.27 1.27)
					(thickness 0.15)
				)
				(justify left bottom)
				(hide yes)
			)
		)
		(property "Datasheet" ""
			(at 331.47 97.79 0)
			(effects
				(font
					(size 1.27 1.27)
					(thickness 0.15)
				)
				(justify left bottom)
				(hide yes)
			)
		)
		(property "Description" ""
			(at 336.55 90.17 0)
			(effects
				(font
					(size 1.27 1.27)
				)
				(hide yes)
			)
		)
		(property "MPN" ""
			(at 336.55 90.17 0)
			(effects
				(font
					(size 1.27 1.27)
					(thickness 0.15)
				)
				(justify left bottom)
				(hide yes)
			)
		)
		(property "Manufacturer" ""
			(at 336.55 90.17 0)
			(effects
				(font
					(size 1.27 1.27)
					(thickness 0.15)
				)
				(justify left bottom)
				(hide yes)
			)
		)
		(property "Author" "Antmicro"
			(at 321.31 74.93 0)
			(effects
				(font
					(size 1.27 1.27)
					(thickness 0.15)
				)
				(justify left bottom)
				(hide yes)
			)
		)
		(property "License" "Apache-2.0"
			(at 321.31 72.39 0)
			(effects
				(font
					(size 1.27 1.27)
					(thickness 0.15)
				)
				(justify left bottom)
				(hide yes)
			)
		)
		(pin "1"
		)
		(instances
			(project "cm4-baseboard"
				(path ""
					(reference "TP915")
					(unit 1)
				)
			)
			(project "usb"
				(path ""
					(reference "TP915")
					(unit 1)
				)
			)
		)
	)
	(symbol
		(lib_id "antmicropower:GND")
		(at 330.2 138.43 0)
		(unit 1)
		(exclude_from_sim no)
		(in_bom yes)
		(on_board yes)
		(dnp no)
		(fields_autoplaced yes)
		(property "Reference" "#PWR0951"
			(at 330.2 144.78 0)
			(effects
				(font
					(size 1.27 1.27)
				)
				(hide yes)
			)
		)
		(property "Value" "GND"
			(at 330.2 142.875 0)
			(effects
				(font
					(size 1.27 1.27)
				)
			)
		)
		(property "Footprint" ""
			(at 339.09 146.05 0)
			(effects
				(font
					(size 1.27 1.27)
					(thickness 0.15)
				)
				(justify left bottom)
				(hide yes)
			)
		)
		(property "Datasheet" ""
			(at 339.09 151.13 0)
			(effects
				(font
					(size 1.27 1.27)
					(thickness 0.15)
				)
				(justify left bottom)
				(hide yes)
			)
		)
		(property "Description" ""
			(at 330.2 138.43 0)
			(effects
				(font
					(size 1.27 1.27)
				)
				(hide yes)
			)
		)
		(property "Author" "Antmicro"
			(at 339.09 146.05 0)
			(effects
				(font
					(size 1.27 1.27)
					(thickness 0.15)
				)
				(justify left bottom)
				(hide yes)
			)
		)
		(property "License" "Apache-2.0"
			(at 339.09 148.59 0)
			(effects
				(font
					(size 1.27 1.27)
					(thickness 0.15)
				)
				(justify left bottom)
				(hide yes)
			)
		)
		(pin "1"
		)
		(instances
			(project "cm4-baseboard"
				(path ""
					(reference "#PWR0951")
					(unit 1)
				)
			)
			(project "usb"
				(path ""
					(reference "#PWR0951")
					(unit 1)
				)
			)
		)
	)
	(symbol
		(lib_id "antmicroResistors0402:R_10k_0402")
		(at 92.71 81.28 270)
		(unit 1)
		(exclude_from_sim no)
		(in_bom yes)
		(on_board yes)
		(dnp no)
		(property "Reference" "R934"
			(at 86.36 85.09 90)
			(effects
				(font
					(size 1.27 1.27)
				)
				(justify left)
			)
		)
		(property "Value" "R_10k_0402"
			(at 80.01 101.6 0)
			(effects
				(font
					(size 1.27 1.27)
					(thickness 0.15)
				)
				(justify left bottom)
				(hide yes)
			)
		)
		(property "Footprint" "antmicro-footprints:R_0402_1005Metric"
			(at 77.47 101.6 0)
			(effects
				(font
					(size 1.27 1.27)
					(thickness 0.15)
				)
				(justify left bottom)
				(hide yes)
			)
		)
		(property "Datasheet" "https://www.bourns.com/docs/product-datasheets/cr.pdf"
			(at 74.93 101.6 0)
			(effects
				(font
					(size 1.27 1.27)
					(thickness 0.15)
				)
				(justify left bottom)
				(hide yes)
			)
		)
		(property "Description" ""
			(at 92.71 81.28 0)
			(effects
				(font
					(size 1.27 1.27)
				)
				(hide yes)
			)
		)
		(property "Manufacturer" "Bourns"
			(at 69.85 101.6 0)
			(effects
				(font
					(size 1.27 1.27)
					(thickness 0.15)
				)
				(justify left bottom)
				(hide yes)
			)
		)
		(property "MPN" "CR0402-FX-1002GLF"
			(at 72.39 101.6 0)
			(effects
				(font
					(size 1.27 1.27)
					(thickness 0.15)
				)
				(justify left bottom)
				(hide yes)
			)
		)
		(property "Val" "10k"
			(at 87.63 82.55 90)
			(effects
				(font
					(size 1.27 1.27)
					(thickness 0.15)
				)
				(justify left)
			)
		)
		(property "License" "Apache-2.0"
			(at 67.31 101.6 0)
			(effects
				(font
					(size 1.27 1.27)
					(thickness 0.15)
				)
				(justify left bottom)
				(hide yes)
			)
		)
		(property "Author" "Antmicro"
			(at 64.77 101.6 0)
			(effects
				(font
					(size 1.27 1.27)
					(thickness 0.15)
				)
				(justify left bottom)
				(hide yes)
			)
		)
		(property "Tolerance" "1%"
			(at 82.55 101.6 0)
			(effects
				(font
					(size 1.27 1.27)
				)
				(justify left bottom)
				(hide yes)
			)
		)
		(pin "1"
		)
		(pin "2"
		)
		(instances
			(project "cm4-baseboard"
				(path ""
					(reference "R934")
					(unit 1)
				)
			)
		)
	)
	(symbol
		(lib_id "antmicroFixedInductors:L_1u_5.5A_Bourns-SRP3212A")
		(at 213.36 54.61 0)
		(unit 1)
		(exclude_from_sim no)
		(in_bom yes)
		(on_board yes)
		(dnp no)
		(fields_autoplaced yes)
		(property "Reference" "L901"
			(at 215.9 49.53 0)
			(effects
				(font
					(size 1.27 1.27)
					(thickness 0.15)
				)
			)
		)
		(property "Value" "L_1u_5.5A_Bourns-SRP3212A"
			(at 215.9 49.53 0)
			(effects
				(font
					(size 1.27 1.27)
					(thickness 0.15)
				)
				(hide yes)
			)
		)
		(property "Footprint" "antmicro-footprints:L_Bourns-SRP3212A"
			(at 227.33 62.23 0)
			(effects
				(font
					(size 1.27 1.27)
					(thickness 0.15)
				)
				(justify left bottom)
				(hide yes)
			)
		)
		(property "Datasheet" "https://www.mouser.com/datasheet/2/54/SRP3212A-3011944.pdf"
			(at 227.33 64.77 0)
			(effects
				(font
					(size 1.27 1.27)
					(thickness 0.15)
				)
				(justify left bottom)
				(hide yes)
			)
		)
		(property "Description" ""
			(at 213.36 54.61 0)
			(effects
				(font
					(size 1.27 1.27)
				)
				(hide yes)
			)
		)
		(property "Manufacturer" "Bourns"
			(at 227.33 67.31 0)
			(effects
				(font
					(size 1.27 1.27)
					(thickness 0.15)
				)
				(justify left bottom)
				(hide yes)
			)
		)
		(property "MPN" "SRP3212A-1R0M"
			(at 227.33 69.85 0)
			(effects
				(font
					(size 1.27 1.27)
					(thickness 0.15)
				)
				(justify left bottom)
				(hide yes)
			)
		)
		(property "Size" "3.2x2.5"
			(at 227.33 77.47 0)
			(effects
				(font
					(size 1.27 1.27)
					(thickness 0.15)
				)
				(justify left bottom)
				(hide yes)
			)
		)
		(property "Val" "1u/5.5A"
			(at 215.9 52.07 0)
			(effects
				(font
					(size 1.27 1.27)
					(thickness 0.15)
				)
			)
		)
		(property "Author" "Antmicro"
			(at 227.33 80.01 0)
			(effects
				(font
					(size 1.27 1.27)
					(thickness 0.15)
				)
				(justify left bottom)
				(hide yes)
			)
		)
		(property "License" "Apache-2.0"
			(at 227.33 82.55 0)
			(effects
				(font
					(size 1.27 1.27)
					(thickness 0.15)
				)
				(justify left bottom)
				(hide yes)
			)
		)
		(property "ISat" "6.5 A"
			(at 227.33 71.12 0)
			(effects
				(font
					(size 1.27 1.27)
				)
				(justify left)
				(hide yes)
			)
		)
		(property "IMax" "5.5 A"
			(at 227.33 74.93 0)
			(effects
				(font
					(size 1.27 1.27)
					(thickness 0.15)
				)
				(justify left bottom)
				(hide yes)
			)
		)
		(pin "1"
		)
		(pin "2"
		)
		(instances
			(project "cm4-baseboard"
				(path ""
					(reference "L901")
					(unit 1)
				)
			)
			(project "usb"
				(path ""
					(reference "L901")
					(unit 1)
				)
			)
		)
	)
	(symbol
		(lib_id "antmicroResistors0402:R_10k_0402")
		(at 313.69 241.3 270)
		(unit 1)
		(exclude_from_sim no)
		(in_bom yes)
		(on_board yes)
		(dnp no)
		(property "Reference" "R929"
			(at 314.96 242.57 90)
			(effects
				(font
					(size 1.27 1.27)
				)
				(justify left)
			)
		)
		(property "Value" "R_10k_0402"
			(at 300.99 261.62 0)
			(effects
				(font
					(size 1.27 1.27)
					(thickness 0.15)
				)
				(justify left bottom)
				(hide yes)
			)
		)
		(property "Footprint" "antmicro-footprints:R_0402_1005Metric"
			(at 298.45 261.62 0)
			(effects
				(font
					(size 1.27 1.27)
					(thickness 0.15)
				)
				(justify left bottom)
				(hide yes)
			)
		)
		(property "Datasheet" "https://www.bourns.com/docs/product-datasheets/cr.pdf"
			(at 295.91 261.62 0)
			(effects
				(font
					(size 1.27 1.27)
					(thickness 0.15)
				)
				(justify left bottom)
				(hide yes)
			)
		)
		(property "Description" ""
			(at 313.69 241.3 0)
			(effects
				(font
					(size 1.27 1.27)
				)
				(hide yes)
			)
		)
		(property "Manufacturer" "Bourns"
			(at 290.83 261.62 0)
			(effects
				(font
					(size 1.27 1.27)
					(thickness 0.15)
				)
				(justify left bottom)
				(hide yes)
			)
		)
		(property "MPN" "CR0402-FX-1002GLF"
			(at 293.37 261.62 0)
			(effects
				(font
					(size 1.27 1.27)
					(thickness 0.15)
				)
				(justify left bottom)
				(hide yes)
			)
		)
		(property "Val" "10k"
			(at 314.96 245.11 90)
			(effects
				(font
					(size 1.27 1.27)
					(thickness 0.15)
				)
				(justify left)
			)
		)
		(property "License" "Apache-2.0"
			(at 288.29 261.62 0)
			(effects
				(font
					(size 1.27 1.27)
					(thickness 0.15)
				)
				(justify left bottom)
				(hide yes)
			)
		)
		(property "Author" "Antmicro"
			(at 285.75 261.62 0)
			(effects
				(font
					(size 1.27 1.27)
					(thickness 0.15)
				)
				(justify left bottom)
				(hide yes)
			)
		)
		(property "Tolerance" "1%"
			(at 303.53 261.62 0)
			(effects
				(font
					(size 1.27 1.27)
				)
				(justify left bottom)
				(hide yes)
			)
		)
		(pin "1"
		)
		(pin "2"
		)
		(instances
			(project "cm4-baseboard"
				(path ""
					(reference "R929")
					(unit 1)
				)
			)
		)
	)
	(symbol
		(lib_id "antmicroFerriteBeadsandChips:FB_120Z_1.3A_Murata-BLM15PD_0402")
		(at 269.24 22.86 0)
		(unit 1)
		(exclude_from_sim no)
		(in_bom yes)
		(on_board yes)
		(dnp no)
		(property "Reference" "FB901"
			(at 271.78 26.67 0)
			(effects
				(font
					(size 1.27 1.27)
				)
			)
		)
		(property "Value" "FB_120Z_1.3A_Murata-BLM15PD_0402"
			(at 271.7419 16.51 0)
			(effects
				(font
					(size 1.27 1.27)
					(thickness 0.15)
				)
				(hide yes)
			)
		)
		(property "Footprint" "antmicro-footprints:FB_0402_1005Metric"
			(at 283.21 30.48 0)
			(effects
				(font
					(size 1.27 1.27)
					(thickness 0.15)
				)
				(justify left bottom)
				(hide yes)
			)
		)
		(property "Datasheet" "https://www.murata.com/en-us/products/productdata/8796740059166/ENFA0018.pdf"
			(at 283.21 33.02 0)
			(effects
				(font
					(size 1.27 1.27)
					(thickness 0.15)
				)
				(justify left bottom)
				(hide yes)
			)
		)
		(property "Description" ""
			(at 269.24 22.86 0)
			(effects
				(font
					(size 1.27 1.27)
				)
				(hide yes)
			)
		)
		(property "MPN" "BLM15PD121SN1D"
			(at 283.21 35.56 0)
			(effects
				(font
					(size 1.27 1.27)
					(thickness 0.15)
				)
				(justify left bottom)
				(hide yes)
			)
		)
		(property "Manufacturer" "Murata"
			(at 283.21 38.1 0)
			(effects
				(font
					(size 1.27 1.27)
					(thickness 0.15)
				)
				(justify left bottom)
				(hide yes)
			)
		)
		(property "Author" "Antmicro"
			(at 283.21 40.64 0)
			(effects
				(font
					(size 1.27 1.27)
					(thickness 0.15)
				)
				(justify left bottom)
				(hide yes)
			)
		)
		(property "License" "Apache-2.0"
			(at 283.21 43.18 0)
			(effects
				(font
					(size 1.27 1.27)
					(thickness 0.15)
				)
				(justify left bottom)
				(hide yes)
			)
		)
		(property "Val" "120Z/1.3A"
			(at 271.7419 29.21 0)
			(effects
				(font
					(size 1.27 1.27)
				)
			)
		)
		(property "Current" ""
			(at 289.56 45.72 0)
			(effects
				(font
					(size 1.27 1.27)
					(thickness 0.15)
				)
				(justify left bottom)
				(hide yes)
			)
		)
		(pin "1"
		)
		(pin "2"
		)
		(instances
			(project "cm4-baseboard"
				(path ""
					(reference "FB901")
					(unit 1)
				)
			)
			(project "usb"
				(path ""
					(reference "FB901")
					(unit 1)
				)
			)
		)
	)
	(symbol
		(lib_id "antmicropower:GND")
		(at 220.98 72.39 0)
		(unit 1)
		(exclude_from_sim no)
		(in_bom yes)
		(on_board yes)
		(dnp no)
		(fields_autoplaced yes)
		(property "Reference" "#PWR0922"
			(at 229.87 74.93 0)
			(effects
				(font
					(size 1.27 1.27)
					(thickness 0.15)
				)
				(justify left bottom)
				(hide yes)
			)
		)
		(property "Value" "GND"
			(at 218.9698 77.47 0)
			(effects
				(font
					(size 1.27 1.27)
					(thickness 0.15)
				)
				(justify left bottom)
			)
		)
		(property "Footprint" ""
			(at 229.87 80.01 0)
			(effects
				(font
					(size 1.27 1.27)
					(thickness 0.15)
				)
				(justify left bottom)
				(hide yes)
			)
		)
		(property "Datasheet" ""
			(at 229.87 85.09 0)
			(effects
				(font
					(size 1.27 1.27)
					(thickness 0.15)
				)
				(justify left bottom)
				(hide yes)
			)
		)
		(property "Description" ""
			(at 220.98 72.39 0)
			(effects
				(font
					(size 1.27 1.27)
				)
				(hide yes)
			)
		)
		(property "Author" "Antmicro"
			(at 229.87 80.01 0)
			(effects
				(font
					(size 1.27 1.27)
					(thickness 0.15)
				)
				(justify left bottom)
				(hide yes)
			)
		)
		(property "License" "Apache-2.0"
			(at 229.87 82.55 0)
			(effects
				(font
					(size 1.27 1.27)
					(thickness 0.15)
				)
				(justify left bottom)
				(hide yes)
			)
		)
		(pin "1"
		)
		(instances
			(project "cm4-baseboard"
				(path ""
					(reference "#PWR0922")
					(unit 1)
				)
			)
			(project "usb"
				(path ""
					(reference "#PWR0922")
					(unit 1)
				)
			)
		)
	)
	(symbol
		(lib_id "antmicroDiodesRectifiersSingle:RB521S30T1G")
		(at 370.84 185.42 0)
		(mirror x)
		(unit 1)
		(exclude_from_sim no)
		(in_bom yes)
		(on_board yes)
		(dnp no)
		(property "Reference" "D908"
			(at 373.38 179.07 0)
			(effects
				(font
					(size 1.27 1.27)
				)
			)
		)
		(property "Value" "RB521S30T1G"
			(at 369.57 187.96 0)
			(effects
				(font
					(size 1.27 1.27)
					(thickness 0.15)
				)
				(justify left bottom)
				(hide yes)
			)
		)
		(property "Footprint" "antmicro-footprints:SOD-523"
			(at 393.7 175.26 0)
			(effects
				(font
					(size 1.27 1.27)
					(thickness 0.15)
				)
				(justify left bottom)
				(hide yes)
			)
		)
		(property "Datasheet" "https://www.onsemi.com/pdf/datasheet/rb521s30t1-d.pdf"
			(at 393.7 172.72 0)
			(effects
				(font
					(size 1.27 1.27)
					(thickness 0.15)
				)
				(justify left bottom)
				(hide yes)
			)
		)
		(property "Description" ""
			(at 370.84 185.42 0)
			(effects
				(font
					(size 1.27 1.27)
				)
				(hide yes)
			)
		)
		(property "MPN" "RB521S30T1G"
			(at 373.38 181.61 0)
			(effects
				(font
					(size 1.27 1.27)
					(thickness 0.15)
				)
			)
		)
		(property "Manufacturer" "ON Semiconductor"
			(at 393.7 167.64 0)
			(effects
				(font
					(size 1.27 1.27)
					(thickness 0.15)
				)
				(justify left bottom)
				(hide yes)
			)
		)
		(property "Author" "Antmicro"
			(at 393.7 165.1 0)
			(effects
				(font
					(size 1.27 1.27)
					(thickness 0.15)
				)
				(justify left bottom)
				(hide yes)
			)
		)
		(property "License" "Apache-2.0"
			(at 393.7 162.56 0)
			(effects
				(font
					(size 1.27 1.27)
					(thickness 0.15)
				)
				(justify left bottom)
				(hide yes)
			)
		)
		(pin "1"
		)
		(pin "2"
		)
		(instances
			(project "cm4-baseboard"
				(path ""
					(reference "D908")
					(unit 1)
				)
			)
		)
	)
	(symbol
		(lib_id "antmicroLogicTranslatorsLevelShifters:NTS0104_DHVQFN")
		(at 344.17 177.8 0)
		(unit 1)
		(exclude_from_sim no)
		(in_bom yes)
		(on_board yes)
		(dnp no)
		(property "Reference" "U904"
			(at 354.33 170.18 0)
			(effects
				(font
					(size 1.27 1.27)
					(thickness 0.15)
				)
			)
		)
		(property "Value" "NTS0104_DHVQFN"
			(at 379.73 185.42 0)
			(effects
				(font
					(size 1.27 1.27)
					(thickness 0.15)
				)
				(justify left bottom)
				(hide yes)
			)
		)
		(property "Footprint" "antmicro-footprints:DHVQFN-14-1EP_2.5x3mm"
			(at 379.73 187.96 0)
			(effects
				(font
					(size 1.27 1.27)
					(thickness 0.15)
				)
				(justify left bottom)
				(hide yes)
			)
		)
		(property "Datasheet" "https://www.nxp.com/docs/en/data-sheet/NTS0104.pdf"
			(at 379.73 190.5 0)
			(effects
				(font
					(size 1.27 1.27)
					(thickness 0.15)
				)
				(justify left bottom)
				(hide yes)
			)
		)
		(property "Description" ""
			(at 344.17 177.8 0)
			(effects
				(font
					(size 1.27 1.27)
				)
				(hide yes)
			)
		)
		(property "MPN" "NTS0104BQ"
			(at 354.33 172.72 0)
			(effects
				(font
					(size 1.27 1.27)
					(thickness 0.15)
				)
			)
		)
		(property "Manufacturer" "NXP"
			(at 379.73 193.04 0)
			(effects
				(font
					(size 1.27 1.27)
					(thickness 0.15)
				)
				(justify left bottom)
				(hide yes)
			)
		)
		(property "Author" "Antmicro"
			(at 379.73 195.58 0)
			(effects
				(font
					(size 1.27 1.27)
					(thickness 0.15)
				)
				(justify left bottom)
				(hide yes)
			)
		)
		(property "License" "Apache-2.0"
			(at 379.73 198.12 0)
			(effects
				(font
					(size 1.27 1.27)
					(thickness 0.15)
				)
				(justify left bottom)
				(hide yes)
			)
		)
		(pin "6"
		)
		(pin "4"
		)
		(pin "9"
		)
		(pin "3"
		)
		(pin "5"
		)
		(pin "15"
		)
		(pin "13"
		)
		(pin "10"
		)
		(pin "8"
		)
		(pin "14"
		)
		(pin "12"
		)
		(pin "11"
		)
		(pin "2"
		)
		(pin "7"
		)
		(pin "1"
		)
		(instances
			(project "cm4-baseboard"
				(path ""
					(reference "U904")
					(unit 1)
				)
			)
		)
	)
	(symbol
		(lib_id "antmicroCapacitors0402:C_18p_0402")
		(at 317.5 133.35 270)
		(unit 1)
		(exclude_from_sim no)
		(in_bom yes)
		(on_board yes)
		(dnp no)
		(property "Reference" "C926"
			(at 314.96 134.62 90)
			(effects
				(font
					(size 1.27 1.27)
				)
				(justify right)
			)
		)
		(property "Value" "C_18p_0402"
			(at 313.69 133.35 0)
			(effects
				(font
					(size 1.27 1.27)
					(thickness 0.15)
				)
				(justify left bottom)
				(hide yes)
			)
		)
		(property "Footprint" "antmicro-footprints:C_0402_1005Metric"
			(at 322.58 138.43 0)
			(effects
				(font
					(size 1.27 1.27)
					(thickness 0.15)
				)
				(justify left bottom)
				(hide yes)
			)
		)
		(property "Datasheet" "https://product.samsungsem.com/mlcc/CL05C180JB51PN.do"
			(at 317.5 133.35 0)
			(effects
				(font
					(size 1.27 1.27)
					(thickness 0.15)
				)
				(justify left bottom)
				(hide yes)
			)
		)
		(property "Description" ""
			(at 317.5 133.35 0)
			(effects
				(font
					(size 1.27 1.27)
				)
				(hide yes)
			)
		)
		(property "Manufacturer" "Samsung Electro-Mechanics"
			(at 327.66 138.43 0)
			(effects
				(font
					(size 1.27 1.27)
					(thickness 0.15)
				)
				(justify left bottom)
				(hide yes)
			)
		)
		(property "MPN" "CL05C180JB51PNC"
			(at 325.12 138.43 0)
			(effects
				(font
					(size 1.27 1.27)
					(thickness 0.15)
				)
				(justify left bottom)
				(hide yes)
			)
		)
		(property "Val" "18p"
			(at 314.96 137.7949 90)
			(effects
				(font
					(size 1.27 1.27)
					(thickness 0.15)
				)
				(justify right)
			)
		)
		(property "License" "Apache-2.0"
			(at 294.64 153.67 0)
			(effects
				(font
					(size 1.27 1.27)
					(thickness 0.15)
				)
				(justify left bottom)
				(hide yes)
			)
		)
		(property "Author" "Antmicro"
			(at 292.1 153.67 0)
			(effects
				(font
					(size 1.27 1.27)
					(thickness 0.15)
				)
				(justify left bottom)
				(hide yes)
			)
		)
		(property "Voltage" ""
			(at 289.56 153.67 0)
			(effects
				(font
					(size 1.27 1.27)
				)
				(justify left bottom)
				(hide yes)
			)
		)
		(property "Dielectric" ""
			(at 287.02 153.67 0)
			(effects
				(font
					(size 1.27 1.27)
				)
				(justify left bottom)
				(hide yes)
			)
		)
		(pin "1"
		)
		(pin "2"
		)
		(instances
			(project "cm4-baseboard"
				(path ""
					(reference "C926")
					(unit 1)
				)
			)
			(project "usb"
				(path ""
					(reference "C926")
					(unit 1)
				)
			)
		)
	)
	(symbol
		(lib_id "antmicropower:GND")
		(at 289.56 45.72 0)
		(unit 1)
		(exclude_from_sim no)
		(in_bom yes)
		(on_board yes)
		(dnp no)
		(property "Reference" "#PWR0945"
			(at 289.56 52.07 0)
			(effects
				(font
					(size 1.27 1.27)
				)
				(hide yes)
			)
		)
		(property "Value" "GND"
			(at 289.56 49.53 0)
			(effects
				(font
					(size 1.27 1.27)
				)
			)
		)
		(property "Footprint" ""
			(at 298.45 53.34 0)
			(effects
				(font
					(size 1.27 1.27)
					(thickness 0.15)
				)
				(justify left bottom)
				(hide yes)
			)
		)
		(property "Datasheet" ""
			(at 298.45 58.42 0)
			(effects
				(font
					(size 1.27 1.27)
					(thickness 0.15)
				)
				(justify left bottom)
				(hide yes)
			)
		)
		(property "Description" ""
			(at 289.56 45.72 0)
			(effects
				(font
					(size 1.27 1.27)
				)
				(hide yes)
			)
		)
		(property "Author" "Antmicro"
			(at 298.45 53.34 0)
			(effects
				(font
					(size 1.27 1.27)
					(thickness 0.15)
				)
				(justify left bottom)
				(hide yes)
			)
		)
		(property "License" "Apache-2.0"
			(at 298.45 55.88 0)
			(effects
				(font
					(size 1.27 1.27)
					(thickness 0.15)
				)
				(justify left bottom)
				(hide yes)
			)
		)
		(pin "1"
		)
		(instances
			(project "cm4-baseboard"
				(path ""
					(reference "#PWR0945")
					(unit 1)
				)
			)
			(project "usb"
				(path ""
					(reference "#PWR0945")
					(unit 1)
				)
			)
		)
	)
	(symbol
		(lib_id "antmicropower:GND")
		(at 342.9 194.31 0)
		(mirror y)
		(unit 1)
		(exclude_from_sim no)
		(in_bom yes)
		(on_board yes)
		(dnp no)
		(property "Reference" "#PWR019"
			(at 334.01 196.85 0)
			(effects
				(font
					(size 1.27 1.27)
					(thickness 0.15)
				)
				(justify left bottom)
				(hide yes)
			)
		)
		(property "Value" "GND"
			(at 342.9 198.12 0)
			(effects
				(font
					(size 1.27 1.27)
					(thickness 0.15)
				)
			)
		)
		(property "Footprint" ""
			(at 334.01 201.93 0)
			(effects
				(font
					(size 1.27 1.27)
					(thickness 0.15)
				)
				(justify left bottom)
				(hide yes)
			)
		)
		(property "Datasheet" ""
			(at 334.01 207.01 0)
			(effects
				(font
					(size 1.27 1.27)
					(thickness 0.15)
				)
				(justify left bottom)
				(hide yes)
			)
		)
		(property "Description" ""
			(at 342.9 194.31 0)
			(effects
				(font
					(size 1.27 1.27)
				)
				(hide yes)
			)
		)
		(property "Author" "Antmicro"
			(at 334.01 201.93 0)
			(effects
				(font
					(size 1.27 1.27)
					(thickness 0.15)
				)
				(justify left bottom)
				(hide yes)
			)
		)
		(property "License" "Apache-2.0"
			(at 334.01 204.47 0)
			(effects
				(font
					(size 1.27 1.27)
					(thickness 0.15)
				)
				(justify left bottom)
				(hide yes)
			)
		)
		(pin "1"
		)
		(instances
			(project "cm4-baseboard"
				(path ""
					(reference "#PWR019")
					(unit 1)
				)
			)
		)
	)
	(symbol
		(lib_id "antmicropower:GND")
		(at 100.33 213.36 0)
		(mirror y)
		(unit 1)
		(exclude_from_sim no)
		(in_bom yes)
		(on_board yes)
		(dnp no)
		(fields_autoplaced yes)
		(property "Reference" "#PWR0909"
			(at 91.44 215.9 0)
			(effects
				(font
					(size 1.27 1.27)
					(thickness 0.15)
				)
				(justify left bottom)
				(hide yes)
			)
		)
		(property "Value" "GND"
			(at 102.3402 218.44 0)
			(effects
				(font
					(size 1.27 1.27)
					(thickness 0.15)
				)
				(justify left bottom)
			)
		)
		(property "Footprint" ""
			(at 91.44 220.98 0)
			(effects
				(font
					(size 1.27 1.27)
					(thickness 0.15)
				)
				(justify left bottom)
				(hide yes)
			)
		)
		(property "Datasheet" ""
			(at 91.44 226.06 0)
			(effects
				(font
					(size 1.27 1.27)
					(thickness 0.15)
				)
				(justify left bottom)
				(hide yes)
			)
		)
		(property "Description" ""
			(at 100.33 213.36 0)
			(effects
				(font
					(size 1.27 1.27)
				)
				(hide yes)
			)
		)
		(property "Author" "Antmicro"
			(at 91.44 220.98 0)
			(effects
				(font
					(size 1.27 1.27)
					(thickness 0.15)
				)
				(justify left bottom)
				(hide yes)
			)
		)
		(property "License" "Apache-2.0"
			(at 91.44 223.52 0)
			(effects
				(font
					(size 1.27 1.27)
					(thickness 0.15)
				)
				(justify left bottom)
				(hide yes)
			)
		)
		(pin "1"
		)
		(instances
			(project "cm4-baseboard"
				(path ""
					(reference "#PWR0909")
					(unit 1)
				)
			)
			(project "usb"
				(path ""
					(reference "#PWR0909")
					(unit 1)
				)
			)
		)
	)
	(symbol
		(lib_id "antmicropower:GND")
		(at 157.48 193.04 0)
		(unit 1)
		(exclude_from_sim no)
		(in_bom yes)
		(on_board yes)
		(dnp no)
		(fields_autoplaced yes)
		(property "Reference" "#PWR0917"
			(at 157.48 199.39 0)
			(effects
				(font
					(size 1.27 1.27)
				)
				(justify left bottom)
				(hide yes)
			)
		)
		(property "Value" "GND"
			(at 157.48 196.85 0)
			(effects
				(font
					(size 1.27 1.27)
				)
			)
		)
		(property "Footprint" ""
			(at 157.48 193.04 0)
			(effects
				(font
					(size 1.27 1.27)
				)
				(hide yes)
			)
		)
		(property "Datasheet" ""
			(at 157.48 193.04 0)
			(effects
				(font
					(size 1.27 1.27)
				)
				(hide yes)
			)
		)
		(property "Description" ""
			(at 157.48 193.04 0)
			(effects
				(font
					(size 1.27 1.27)
				)
				(hide yes)
			)
		)
		(property "Author" "Antmicro"
			(at 166.37 200.66 0)
			(effects
				(font
					(size 1.27 1.27)
					(thickness 0.15)
				)
				(justify left bottom)
				(hide yes)
			)
		)
		(property "License" "Apache-2.0"
			(at 166.37 203.2 0)
			(effects
				(font
					(size 1.27 1.27)
					(thickness 0.15)
				)
				(justify left bottom)
				(hide yes)
			)
		)
		(pin "1"
		)
		(instances
			(project "cm4-baseboard"
				(path ""
					(reference "#PWR0917")
					(unit 1)
				)
			)
			(project "usb"
				(path ""
					(reference "#PWR0917")
					(unit 1)
				)
			)
		)
	)
	(symbol
		(lib_id "antmicropower:GND")
		(at 323.85 138.43 0)
		(unit 1)
		(exclude_from_sim no)
		(in_bom yes)
		(on_board yes)
		(dnp no)
		(fields_autoplaced yes)
		(property "Reference" "#PWR0950"
			(at 323.85 144.78 0)
			(effects
				(font
					(size 1.27 1.27)
				)
				(hide yes)
			)
		)
		(property "Value" "GND"
			(at 323.85 142.875 0)
			(effects
				(font
					(size 1.27 1.27)
				)
			)
		)
		(property "Footprint" ""
			(at 332.74 146.05 0)
			(effects
				(font
					(size 1.27 1.27)
					(thickness 0.15)
				)
				(justify left bottom)
				(hide yes)
			)
		)
		(property "Datasheet" ""
			(at 332.74 151.13 0)
			(effects
				(font
					(size 1.27 1.27)
					(thickness 0.15)
				)
				(justify left bottom)
				(hide yes)
			)
		)
		(property "Description" ""
			(at 323.85 138.43 0)
			(effects
				(font
					(size 1.27 1.27)
				)
				(hide yes)
			)
		)
		(property "Author" "Antmicro"
			(at 332.74 146.05 0)
			(effects
				(font
					(size 1.27 1.27)
					(thickness 0.15)
				)
				(justify left bottom)
				(hide yes)
			)
		)
		(property "License" "Apache-2.0"
			(at 332.74 148.59 0)
			(effects
				(font
					(size 1.27 1.27)
					(thickness 0.15)
				)
				(justify left bottom)
				(hide yes)
			)
		)
		(pin "1"
		)
		(instances
			(project "cm4-baseboard"
				(path ""
					(reference "#PWR0950")
					(unit 1)
				)
			)
			(project "usb"
				(path ""
					(reference "#PWR0950")
					(unit 1)
				)
			)
		)
	)
	(symbol
		(lib_id "antmicroCapacitors0402:C_100n_0402")
		(at 281.94 39.37 270)
		(unit 1)
		(exclude_from_sim no)
		(in_bom yes)
		(on_board yes)
		(dnp no)
		(property "Reference" "C918"
			(at 282.575 40.005 90)
			(effects
				(font
					(size 1.27 1.27)
				)
				(justify left)
			)
		)
		(property "Value" "C_100n_0402"
			(at 278.13 39.37 0)
			(effects
				(font
					(size 1.27 1.27)
					(thickness 0.15)
				)
				(justify left bottom)
				(hide yes)
			)
		)
		(property "Footprint" "antmicro-footprints:C_0402_1005Metric"
			(at 287.02 44.45 0)
			(effects
				(font
					(size 1.27 1.27)
					(thickness 0.15)
				)
				(justify left bottom)
				(hide yes)
			)
		)
		(property "Datasheet" "https://www.murata.com/products/productdetail?partno=GRM155R61H104KE14%23"
			(at 281.94 39.37 0)
			(effects
				(font
					(size 1.27 1.27)
					(thickness 0.15)
				)
				(justify left bottom)
				(hide yes)
			)
		)
		(property "Description" ""
			(at 281.94 39.37 0)
			(effects
				(font
					(size 1.27 1.27)
				)
				(hide yes)
			)
		)
		(property "Manufacturer" "Murata"
			(at 292.1 44.45 0)
			(effects
				(font
					(size 1.27 1.27)
					(thickness 0.15)
				)
				(justify left bottom)
				(hide yes)
			)
		)
		(property "MPN" "GRM155R61H104KE14D"
			(at 289.56 44.45 0)
			(effects
				(font
					(size 1.27 1.27)
					(thickness 0.15)
				)
				(justify left bottom)
				(hide yes)
			)
		)
		(property "Val" "100n"
			(at 282.575 43.815 90)
			(effects
				(font
					(size 1.27 1.27)
					(thickness 0.15)
				)
				(justify left)
			)
		)
		(property "License" "Apache-2.0"
			(at 259.08 59.69 0)
			(effects
				(font
					(size 1.27 1.27)
					(thickness 0.15)
				)
				(justify left bottom)
				(hide yes)
			)
		)
		(property "Author" "Antmicro"
			(at 256.54 59.69 0)
			(effects
				(font
					(size 1.27 1.27)
					(thickness 0.15)
				)
				(justify left bottom)
				(hide yes)
			)
		)
		(property "Voltage" "50V"
			(at 254 59.69 0)
			(effects
				(font
					(size 1.27 1.27)
				)
				(justify left bottom)
				(hide yes)
			)
		)
		(property "Dielectric" "X5R"
			(at 251.46 59.69 0)
			(effects
				(font
					(size 1.27 1.27)
				)
				(justify left bottom)
				(hide yes)
			)
		)
		(pin "1"
		)
		(pin "2"
		)
		(instances
			(project "cm4-baseboard"
				(path ""
					(reference "C918")
					(unit 1)
				)
			)
			(project "usb"
				(path ""
					(reference "C918")
					(unit 1)
				)
			)
		)
	)
	(symbol
		(lib_id "antmicropower:GND")
		(at 372.11 207.01 0)
		(unit 1)
		(exclude_from_sim no)
		(in_bom yes)
		(on_board yes)
		(dnp no)
		(fields_autoplaced yes)
		(property "Reference" "#PWR020"
			(at 381 209.55 0)
			(effects
				(font
					(size 1.27 1.27)
					(thickness 0.15)
				)
				(justify left bottom)
				(hide yes)
			)
		)
		(property "Value" "GND"
			(at 372.11 211.455 0)
			(effects
				(font
					(size 1.27 1.27)
					(thickness 0.15)
				)
			)
		)
		(property "Footprint" ""
			(at 381 214.63 0)
			(effects
				(font
					(size 1.27 1.27)
					(thickness 0.15)
				)
				(justify left bottom)
				(hide yes)
			)
		)
		(property "Datasheet" ""
			(at 381 219.71 0)
			(effects
				(font
					(size 1.27 1.27)
					(thickness 0.15)
				)
				(justify left bottom)
				(hide yes)
			)
		)
		(property "Description" ""
			(at 372.11 207.01 0)
			(effects
				(font
					(size 1.27 1.27)
				)
				(hide yes)
			)
		)
		(property "Author" "Antmicro"
			(at 381 214.63 0)
			(effects
				(font
					(size 1.27 1.27)
					(thickness 0.15)
				)
				(justify left bottom)
				(hide yes)
			)
		)
		(property "License" "Apache-2.0"
			(at 381 217.17 0)
			(effects
				(font
					(size 1.27 1.27)
					(thickness 0.15)
				)
				(justify left bottom)
				(hide yes)
			)
		)
		(pin "1"
		)
		(instances
			(project "cm4-baseboard"
				(path ""
					(reference "#PWR020")
					(unit 1)
				)
			)
		)
	)
	(symbol
		(lib_id "antmicropower:GND")
		(at 340.36 223.52 0)
		(mirror y)
		(unit 1)
		(exclude_from_sim no)
		(in_bom yes)
		(on_board yes)
		(dnp no)
		(property "Reference" "#PWR0926"
			(at 331.47 226.06 0)
			(effects
				(font
					(size 1.27 1.27)
					(thickness 0.15)
				)
				(justify left bottom)
				(hide yes)
			)
		)
		(property "Value" "GND"
			(at 340.36 227.33 0)
			(effects
				(font
					(size 1.27 1.27)
					(thickness 0.15)
				)
			)
		)
		(property "Footprint" ""
			(at 331.47 231.14 0)
			(effects
				(font
					(size 1.27 1.27)
					(thickness 0.15)
				)
				(justify left bottom)
				(hide yes)
			)
		)
		(property "Datasheet" ""
			(at 331.47 236.22 0)
			(effects
				(font
					(size 1.27 1.27)
					(thickness 0.15)
				)
				(justify left bottom)
				(hide yes)
			)
		)
		(property "Description" ""
			(at 340.36 223.52 0)
			(effects
				(font
					(size 1.27 1.27)
				)
				(hide yes)
			)
		)
		(property "Author" "Antmicro"
			(at 331.47 231.14 0)
			(effects
				(font
					(size 1.27 1.27)
					(thickness 0.15)
				)
				(justify left bottom)
				(hide yes)
			)
		)
		(property "License" "Apache-2.0"
			(at 331.47 233.68 0)
			(effects
				(font
					(size 1.27 1.27)
					(thickness 0.15)
				)
				(justify left bottom)
				(hide yes)
			)
		)
		(pin "1"
		)
		(instances
			(project "cm4-baseboard"
				(path ""
					(reference "#PWR0926")
					(unit 1)
				)
			)
		)
	)
	(symbol
		(lib_id "antmicroTransistorsFETsMOSFETsSingle:PJE138K")
		(at 96.52 83.82 0)
		(unit 1)
		(exclude_from_sim no)
		(in_bom yes)
		(on_board yes)
		(dnp no)
		(property "Reference" "Q906"
			(at 96.52 86.36 0)
			(effects
				(font
					(size 1.27 1.27)
				)
				(justify left)
			)
		)
		(property "Value" "PJE138K"
			(at 106.68 86.36 90)
			(effects
				(font
					(size 1.27 1.27)
				)
				(justify left)
			)
		)
		(property "Footprint" "antmicro-footprints:SOT-523"
			(at 101.6 78.74 0)
			(effects
				(font
					(size 1.524 1.524)
				)
				(justify left bottom)
				(hide yes)
			)
		)
		(property "Datasheet" "https://www.mouser.com/datasheet/2/1057/PJE138K-1876698.pdf"
			(at 101.6 76.2 0)
			(effects
				(font
					(size 1.524 1.524)
				)
				(justify left bottom)
				(hide yes)
			)
		)
		(property "Description" ""
			(at 96.52 83.82 0)
			(effects
				(font
					(size 1.27 1.27)
				)
				(hide yes)
			)
		)
		(property "MPN" "PJE138K_R1_00001"
			(at 113.03 73.66 0)
			(effects
				(font
					(size 1.524 1.524)
				)
				(justify left bottom)
				(hide yes)
			)
		)
		(property "Manufacturer" "PANJIT"
			(at 101.6 73.66 0)
			(effects
				(font
					(size 1.524 1.524)
				)
				(justify left bottom)
				(hide yes)
			)
		)
		(property "Author" "Antmicro"
			(at 119.38 105.41 0)
			(effects
				(font
					(size 1.27 1.27)
					(thickness 0.15)
				)
				(justify left bottom)
				(hide yes)
			)
		)
		(property "License" "Apache-2.0"
			(at 119.38 107.95 0)
			(effects
				(font
					(size 1.27 1.27)
					(thickness 0.15)
				)
				(justify left bottom)
				(hide yes)
			)
		)
		(pin "1"
		)
		(pin "2"
		)
		(pin "3"
		)
		(instances
			(project "cm4-baseboard"
				(path ""
					(reference "Q906")
					(unit 1)
				)
			)
		)
	)
	(symbol
		(lib_id "antmicroResistors0402:R_10k_0402")
		(at 325.12 224.79 270)
		(unit 1)
		(exclude_from_sim no)
		(in_bom yes)
		(on_board yes)
		(dnp no)
		(property "Reference" "R930"
			(at 326.39 224.79 90)
			(effects
				(font
					(size 1.27 1.27)
				)
				(justify left)
			)
		)
		(property "Value" "R_10k_0402"
			(at 312.42 245.11 0)
			(effects
				(font
					(size 1.27 1.27)
					(thickness 0.15)
				)
				(justify left bottom)
				(hide yes)
			)
		)
		(property "Footprint" "antmicro-footprints:R_0402_1005Metric"
			(at 309.88 245.11 0)
			(effects
				(font
					(size 1.27 1.27)
					(thickness 0.15)
				)
				(justify left bottom)
				(hide yes)
			)
		)
		(property "Datasheet" "https://www.bourns.com/docs/product-datasheets/cr.pdf"
			(at 307.34 245.11 0)
			(effects
				(font
					(size 1.27 1.27)
					(thickness 0.15)
				)
				(justify left bottom)
				(hide yes)
			)
		)
		(property "Description" ""
			(at 325.12 224.79 0)
			(effects
				(font
					(size 1.27 1.27)
				)
				(hide yes)
			)
		)
		(property "Manufacturer" "Bourns"
			(at 302.26 245.11 0)
			(effects
				(font
					(size 1.27 1.27)
					(thickness 0.15)
				)
				(justify left bottom)
				(hide yes)
			)
		)
		(property "MPN" "CR0402-FX-1002GLF"
			(at 304.8 245.11 0)
			(effects
				(font
					(size 1.27 1.27)
					(thickness 0.15)
				)
				(justify left bottom)
				(hide yes)
			)
		)
		(property "Val" "10k"
			(at 326.39 227.33 90)
			(effects
				(font
					(size 1.27 1.27)
					(thickness 0.15)
				)
				(justify left)
			)
		)
		(property "License" "Apache-2.0"
			(at 299.72 245.11 0)
			(effects
				(font
					(size 1.27 1.27)
					(thickness 0.15)
				)
				(justify left bottom)
				(hide yes)
			)
		)
		(property "Author" "Antmicro"
			(at 297.18 245.11 0)
			(effects
				(font
					(size 1.27 1.27)
					(thickness 0.15)
				)
				(justify left bottom)
				(hide yes)
			)
		)
		(property "Tolerance" "1%"
			(at 314.96 245.11 0)
			(effects
				(font
					(size 1.27 1.27)
				)
				(justify left bottom)
				(hide yes)
			)
		)
		(pin "1"
		)
		(pin "2"
		)
		(instances
			(project "cm4-baseboard"
				(path ""
					(reference "R930")
					(unit 1)
				)
			)
		)
	)
	(symbol
		(lib_id "antmicroResistors0402:R_2k2_0402")
		(at 220.98 71.12 270)
		(mirror x)
		(unit 1)
		(exclude_from_sim no)
		(in_bom yes)
		(on_board yes)
		(dnp no)
		(fields_autoplaced yes)
		(property "Reference" "R913"
			(at 218.44 67.31 90)
			(effects
				(font
					(size 1.27 1.27)
					(thickness 0.15)
				)
				(justify right)
			)
		)
		(property "Value" "R_2k2_0402"
			(at 208.28 50.8 0)
			(effects
				(font
					(size 1.27 1.27)
					(thickness 0.15)
				)
				(justify left bottom)
				(hide yes)
			)
		)
		(property "Footprint" "antmicro-footprints:R_0402_1005Metric"
			(at 205.74 50.8 0)
			(effects
				(font
					(size 1.27 1.27)
					(thickness 0.15)
				)
				(justify left bottom)
				(hide yes)
			)
		)
		(property "Datasheet" "https://www.bourns.com/docs/product-datasheets/cr.pdf"
			(at 203.2 50.8 0)
			(effects
				(font
					(size 1.27 1.27)
					(thickness 0.15)
				)
				(justify left bottom)
				(hide yes)
			)
		)
		(property "Description" ""
			(at 220.98 71.12 0)
			(effects
				(font
					(size 1.27 1.27)
				)
				(hide yes)
			)
		)
		(property "MPN" "CR0402-FX-2201GLF"
			(at 200.66 50.8 0)
			(effects
				(font
					(size 1.27 1.27)
					(thickness 0.15)
				)
				(justify left bottom)
				(hide yes)
			)
		)
		(property "Manufacturer" "Bourns"
			(at 198.12 50.8 0)
			(effects
				(font
					(size 1.27 1.27)
					(thickness 0.15)
				)
				(justify left bottom)
				(hide yes)
			)
		)
		(property "License" "Apache-2.0"
			(at 195.58 50.8 0)
			(effects
				(font
					(size 1.27 1.27)
					(thickness 0.15)
				)
				(justify left bottom)
				(hide yes)
			)
		)
		(property "Author" "Antmicro"
			(at 193.04 50.8 0)
			(effects
				(font
					(size 1.27 1.27)
					(thickness 0.15)
				)
				(justify left bottom)
				(hide yes)
			)
		)
		(property "Val" "2k2"
			(at 218.44 69.85 90)
			(effects
				(font
					(size 1.27 1.27)
					(thickness 0.15)
				)
				(justify right)
			)
		)
		(property "Tolerance" "1%"
			(at 210.82 50.8 0)
			(effects
				(font
					(size 1.27 1.27)
				)
				(justify left bottom)
				(hide yes)
			)
		)
		(pin "2"
		)
		(pin "1"
		)
		(instances
			(project "cm4-baseboard"
				(path ""
					(reference "R913")
					(unit 1)
				)
			)
			(project "usb"
				(path ""
					(reference "R913")
					(unit 1)
				)
			)
		)
	)
	(symbol
		(lib_id "antmicropower:GND")
		(at 285.75 156.21 0)
		(unit 1)
		(exclude_from_sim no)
		(in_bom yes)
		(on_board yes)
		(dnp no)
		(fields_autoplaced yes)
		(property "Reference" "#PWR0944"
			(at 285.75 162.56 0)
			(effects
				(font
					(size 1.27 1.27)
				)
				(hide yes)
			)
		)
		(property "Value" "GND"
			(at 285.75 161.29 0)
			(effects
				(font
					(size 1.27 1.27)
				)
			)
		)
		(property "Footprint" ""
			(at 294.64 163.83 0)
			(effects
				(font
					(size 1.27 1.27)
					(thickness 0.15)
				)
				(justify left bottom)
				(hide yes)
			)
		)
		(property "Datasheet" ""
			(at 294.64 168.91 0)
			(effects
				(font
					(size 1.27 1.27)
					(thickness 0.15)
				)
				(justify left bottom)
				(hide yes)
			)
		)
		(property "Description" ""
			(at 285.75 156.21 0)
			(effects
				(font
					(size 1.27 1.27)
				)
				(hide yes)
			)
		)
		(property "Author" "Antmicro"
			(at 294.64 163.83 0)
			(effects
				(font
					(size 1.27 1.27)
					(thickness 0.15)
				)
				(justify left bottom)
				(hide yes)
			)
		)
		(property "License" "Apache-2.0"
			(at 294.64 166.37 0)
			(effects
				(font
					(size 1.27 1.27)
					(thickness 0.15)
				)
				(justify left bottom)
				(hide yes)
			)
		)
		(pin "1"
		)
		(instances
			(project "cm4-baseboard"
				(path ""
					(reference "#PWR0944")
					(unit 1)
				)
			)
			(project "usb"
				(path ""
					(reference "#PWR0944")
					(unit 1)
				)
			)
		)
	)
	(symbol
		(lib_id "antmicropower:GND")
		(at 365.76 194.31 0)
		(unit 1)
		(exclude_from_sim no)
		(in_bom yes)
		(on_board yes)
		(dnp no)
		(property "Reference" "#PWR018"
			(at 374.65 196.85 0)
			(effects
				(font
					(size 1.27 1.27)
					(thickness 0.15)
				)
				(justify left bottom)
				(hide yes)
			)
		)
		(property "Value" "GND"
			(at 365.76 198.12 0)
			(effects
				(font
					(size 1.27 1.27)
					(thickness 0.15)
				)
			)
		)
		(property "Footprint" ""
			(at 374.65 201.93 0)
			(effects
				(font
					(size 1.27 1.27)
					(thickness 0.15)
				)
				(justify left bottom)
				(hide yes)
			)
		)
		(property "Datasheet" ""
			(at 374.65 207.01 0)
			(effects
				(font
					(size 1.27 1.27)
					(thickness 0.15)
				)
				(justify left bottom)
				(hide yes)
			)
		)
		(property "Description" ""
			(at 365.76 194.31 0)
			(effects
				(font
					(size 1.27 1.27)
				)
				(hide yes)
			)
		)
		(property "Author" "Antmicro"
			(at 374.65 201.93 0)
			(effects
				(font
					(size 1.27 1.27)
					(thickness 0.15)
				)
				(justify left bottom)
				(hide yes)
			)
		)
		(property "License" "Apache-2.0"
			(at 374.65 204.47 0)
			(effects
				(font
					(size 1.27 1.27)
					(thickness 0.15)
				)
				(justify left bottom)
				(hide yes)
			)
		)
		(pin "1"
		)
		(instances
			(project "cm4-baseboard"
				(path ""
					(reference "#PWR018")
					(unit 1)
				)
			)
		)
	)
	(symbol
		(lib_id "antmicropower:GND")
		(at 86.36 66.04 0)
		(unit 1)
		(exclude_from_sim no)
		(in_bom yes)
		(on_board yes)
		(dnp no)
		(fields_autoplaced yes)
		(property "Reference" "#PWR0912"
			(at 95.25 68.58 0)
			(effects
				(font
					(size 1.27 1.27)
					(thickness 0.15)
				)
				(justify left bottom)
				(hide yes)
			)
		)
		(property "Value" "GND"
			(at 84.3498 71.12 0)
			(effects
				(font
					(size 1.27 1.27)
					(thickness 0.15)
				)
				(justify left bottom)
			)
		)
		(property "Footprint" ""
			(at 95.25 73.66 0)
			(effects
				(font
					(size 1.27 1.27)
					(thickness 0.15)
				)
				(justify left bottom)
				(hide yes)
			)
		)
		(property "Datasheet" ""
			(at 95.25 78.74 0)
			(effects
				(font
					(size 1.27 1.27)
					(thickness 0.15)
				)
				(justify left bottom)
				(hide yes)
			)
		)
		(property "Description" ""
			(at 86.36 66.04 0)
			(effects
				(font
					(size 1.27 1.27)
				)
				(hide yes)
			)
		)
		(property "Author" "Antmicro"
			(at 95.25 73.66 0)
			(effects
				(font
					(size 1.27 1.27)
					(thickness 0.15)
				)
				(justify left bottom)
				(hide yes)
			)
		)
		(property "License" "Apache-2.0"
			(at 95.25 76.2 0)
			(effects
				(font
					(size 1.27 1.27)
					(thickness 0.15)
				)
				(justify left bottom)
				(hide yes)
			)
		)
		(pin "1"
		)
		(instances
			(project "cm4-baseboard"
				(path ""
					(reference "#PWR0912")
					(unit 1)
				)
			)
			(project "usb"
				(path ""
					(reference "#PWR0912")
					(unit 1)
				)
			)
		)
	)
	(symbol
		(lib_id "antmicroTransistorsFETsMOSFETsSingle:SQS401EN-T1_BE3")
		(at 120.65 64.77 270)
		(mirror x)
		(unit 1)
		(exclude_from_sim no)
		(in_bom yes)
		(on_board yes)
		(dnp no)
		(fields_autoplaced yes)
		(property "Reference" "Q902"
			(at 123.19 50.8 90)
			(effects
				(font
					(size 1.27 1.27)
					(thickness 0.15)
				)
			)
		)
		(property "Value" "SQS401EN-T1_BE3"
			(at 110.49 49.53 0)
			(effects
				(font
					(size 1.27 1.27)
					(thickness 0.15)
				)
				(justify left bottom)
				(hide yes)
			)
		)
		(property "Footprint" "antmicro-footprints:Vishay_PowerPAK_1212-8_Single"
			(at 107.95 49.53 0)
			(effects
				(font
					(size 1.27 1.27)
					(thickness 0.15)
				)
				(justify left bottom)
				(hide yes)
			)
		)
		(property "Datasheet" "https://www.vishay.com/docs/65529/sqs401en.pdf"
			(at 105.41 49.53 0)
			(effects
				(font
					(size 1.27 1.27)
					(thickness 0.15)
				)
				(justify left bottom)
				(hide yes)
			)
		)
		(property "Description" ""
			(at 120.65 64.77 0)
			(effects
				(font
					(size 1.27 1.27)
				)
				(hide yes)
			)
		)
		(property "MPN" "SQS401EN-T1_BE3"
			(at 123.19 53.34 90)
			(effects
				(font
					(size 1.27 1.27)
					(thickness 0.15)
				)
			)
		)
		(property "Manufacturer" "Vishay"
			(at 102.87 49.53 0)
			(effects
				(font
					(size 1.27 1.27)
					(thickness 0.15)
				)
				(justify left bottom)
				(hide yes)
			)
		)
		(property "Author" "Antmicro"
			(at 100.33 49.53 0)
			(effects
				(font
					(size 1.27 1.27)
					(thickness 0.15)
				)
				(justify left bottom)
				(hide yes)
			)
		)
		(property "License" "Apache-2.0"
			(at 97.79 49.53 0)
			(effects
				(font
					(size 1.27 1.27)
					(thickness 0.15)
				)
				(justify left bottom)
				(hide yes)
			)
		)
		(pin "1"
		)
		(pin "2"
		)
		(pin "3"
		)
		(pin "4"
		)
		(pin "5"
		)
		(instances
			(project "cm4-baseboard"
				(path ""
					(reference "Q902")
					(unit 1)
				)
			)
			(project "usb"
				(path ""
					(reference "Q902")
					(unit 1)
				)
			)
		)
	)
	(symbol
		(lib_id "antmicropower:GND")
		(at 278.13 156.21 0)
		(unit 1)
		(exclude_from_sim no)
		(in_bom yes)
		(on_board yes)
		(dnp no)
		(fields_autoplaced yes)
		(property "Reference" "#PWR0939"
			(at 278.13 162.56 0)
			(effects
				(font
					(size 1.27 1.27)
				)
				(hide yes)
			)
		)
		(property "Value" "GND"
			(at 278.13 161.29 0)
			(effects
				(font
					(size 1.27 1.27)
				)
			)
		)
		(property "Footprint" ""
			(at 287.02 163.83 0)
			(effects
				(font
					(size 1.27 1.27)
					(thickness 0.15)
				)
				(justify left bottom)
				(hide yes)
			)
		)
		(property "Datasheet" ""
			(at 287.02 168.91 0)
			(effects
				(font
					(size 1.27 1.27)
					(thickness 0.15)
				)
				(justify left bottom)
				(hide yes)
			)
		)
		(property "Description" ""
			(at 278.13 156.21 0)
			(effects
				(font
					(size 1.27 1.27)
				)
				(hide yes)
			)
		)
		(property "Author" "Antmicro"
			(at 287.02 163.83 0)
			(effects
				(font
					(size 1.27 1.27)
					(thickness 0.15)
				)
				(justify left bottom)
				(hide yes)
			)
		)
		(property "License" "Apache-2.0"
			(at 287.02 166.37 0)
			(effects
				(font
					(size 1.27 1.27)
					(thickness 0.15)
				)
				(justify left bottom)
				(hide yes)
			)
		)
		(pin "1"
		)
		(instances
			(project "cm4-baseboard"
				(path ""
					(reference "#PWR0939")
					(unit 1)
				)
			)
			(project "usb"
				(path ""
					(reference "#PWR0939")
					(unit 1)
				)
			)
		)
	)
	(symbol
		(lib_id "antmicropower:GND")
		(at 325.12 247.65 0)
		(unit 1)
		(exclude_from_sim no)
		(in_bom yes)
		(on_board yes)
		(dnp no)
		(property "Reference" "#PWR06"
			(at 334.01 250.19 0)
			(effects
				(font
					(size 1.27 1.27)
					(thickness 0.15)
				)
				(justify left bottom)
				(hide yes)
			)
		)
		(property "Value" "GND"
			(at 325.12 251.46 0)
			(effects
				(font
					(size 1.27 1.27)
					(thickness 0.15)
				)
			)
		)
		(property "Footprint" ""
			(at 334.01 255.27 0)
			(effects
				(font
					(size 1.27 1.27)
					(thickness 0.15)
				)
				(justify left bottom)
				(hide yes)
			)
		)
		(property "Datasheet" ""
			(at 334.01 260.35 0)
			(effects
				(font
					(size 1.27 1.27)
					(thickness 0.15)
				)
				(justify left bottom)
				(hide yes)
			)
		)
		(property "Description" ""
			(at 325.12 247.65 0)
			(effects
				(font
					(size 1.27 1.27)
				)
				(hide yes)
			)
		)
		(property "Author" "Antmicro"
			(at 334.01 255.27 0)
			(effects
				(font
					(size 1.27 1.27)
					(thickness 0.15)
				)
				(justify left bottom)
				(hide yes)
			)
		)
		(property "License" "Apache-2.0"
			(at 334.01 257.81 0)
			(effects
				(font
					(size 1.27 1.27)
					(thickness 0.15)
				)
				(justify left bottom)
				(hide yes)
			)
		)
		(pin "1"
		)
		(instances
			(project "cm4-baseboard"
				(path ""
					(reference "#PWR06")
					(unit 1)
				)
			)
		)
	)
	(symbol
		(lib_id "antmicroResistors0402:R_10k_0402")
		(at 328.93 177.8 270)
		(mirror x)
		(unit 1)
		(exclude_from_sim no)
		(in_bom no)
		(on_board yes)
		(dnp yes)
		(property "Reference" "R932"
			(at 326.39 173.99 90)
			(effects
				(font
					(size 1.27 1.27)
				)
				(justify right)
			)
		)
		(property "Value" "R_10k_0402"
			(at 316.23 157.48 0)
			(effects
				(font
					(size 1.27 1.27)
					(thickness 0.15)
				)
				(justify left bottom)
				(hide yes)
			)
		)
		(property "Footprint" "antmicro-footprints:R_0402_1005Metric"
			(at 313.69 157.48 0)
			(effects
				(font
					(size 1.27 1.27)
					(thickness 0.15)
				)
				(justify left bottom)
				(hide yes)
			)
		)
		(property "Datasheet" "https://www.bourns.com/docs/product-datasheets/cr.pdf"
			(at 311.15 157.48 0)
			(effects
				(font
					(size 1.27 1.27)
					(thickness 0.15)
				)
				(justify left bottom)
				(hide yes)
			)
		)
		(property "Description" ""
			(at 328.93 177.8 0)
			(effects
				(font
					(size 1.27 1.27)
				)
				(hide yes)
			)
		)
		(property "Manufacturer" "Bourns"
			(at 306.07 157.48 0)
			(effects
				(font
					(size 1.27 1.27)
					(thickness 0.15)
				)
				(justify left bottom)
				(hide yes)
			)
		)
		(property "MPN" "CR0402-FX-1002GLF"
			(at 308.61 157.48 0)
			(effects
				(font
					(size 1.27 1.27)
					(thickness 0.15)
				)
				(justify left bottom)
				(hide yes)
			)
		)
		(property "Val" "10k"
			(at 326.39 176.53 90)
			(effects
				(font
					(size 1.27 1.27)
					(thickness 0.15)
				)
				(justify right)
			)
		)
		(property "License" "Apache-2.0"
			(at 303.53 157.48 0)
			(effects
				(font
					(size 1.27 1.27)
					(thickness 0.15)
				)
				(justify left bottom)
				(hide yes)
			)
		)
		(property "Author" "Antmicro"
			(at 300.99 157.48 0)
			(effects
				(font
					(size 1.27 1.27)
					(thickness 0.15)
				)
				(justify left bottom)
				(hide yes)
			)
		)
		(property "Tolerance" "1%"
			(at 318.77 157.48 0)
			(effects
				(font
					(size 1.27 1.27)
				)
				(justify left bottom)
				(hide yes)
			)
		)
		(pin "1"
		)
		(pin "2"
		)
		(instances
			(project "cm4-baseboard"
				(path ""
					(reference "R932")
					(unit 1)
				)
			)
		)
	)
	(symbol
		(lib_id "antmicroTestPoints:TP_0.75mm_SMD")
		(at 336.55 85.09 180)
		(unit 1)
		(exclude_from_sim no)
		(in_bom no)
		(on_board yes)
		(dnp no)
		(property "Reference" "TP913"
			(at 331.47 85.09 0)
			(effects
				(font
					(size 1.27 1.27)
				)
				(justify left)
			)
		)
		(property "Value" "TP_0.75mm_SMD"
			(at 336.55 82.55 0)
			(effects
				(font
					(size 1.27 1.27)
					(thickness 0.15)
				)
				(justify left bottom)
				(hide yes)
			)
		)
		(property "Footprint" "antmicro-footprints:TP_SMD_0.75mm"
			(at 331.47 90.17 0)
			(effects
				(font
					(size 1.27 1.27)
					(thickness 0.15)
				)
				(justify left bottom)
				(hide yes)
			)
		)
		(property "Datasheet" ""
			(at 331.47 92.71 0)
			(effects
				(font
					(size 1.27 1.27)
					(thickness 0.15)
				)
				(justify left bottom)
				(hide yes)
			)
		)
		(property "Description" ""
			(at 336.55 85.09 0)
			(effects
				(font
					(size 1.27 1.27)
				)
				(hide yes)
			)
		)
		(property "MPN" ""
			(at 336.55 85.09 0)
			(effects
				(font
					(size 1.27 1.27)
					(thickness 0.15)
				)
				(justify left bottom)
				(hide yes)
			)
		)
		(property "Manufacturer" ""
			(at 336.55 85.09 0)
			(effects
				(font
					(size 1.27 1.27)
					(thickness 0.15)
				)
				(justify left bottom)
				(hide yes)
			)
		)
		(property "Author" "Antmicro"
			(at 321.31 69.85 0)
			(effects
				(font
					(size 1.27 1.27)
					(thickness 0.15)
				)
				(justify left bottom)
				(hide yes)
			)
		)
		(property "License" "Apache-2.0"
			(at 321.31 67.31 0)
			(effects
				(font
					(size 1.27 1.27)
					(thickness 0.15)
				)
				(justify left bottom)
				(hide yes)
			)
		)
		(pin "1"
		)
		(instances
			(project "cm4-baseboard"
				(path ""
					(reference "TP913")
					(unit 1)
				)
			)
			(project "usb"
				(path ""
					(reference "TP913")
					(unit 1)
				)
			)
		)
	)
	(symbol
		(lib_id "antmicropower:GND")
		(at 194.31 194.31 0)
		(mirror y)
		(unit 1)
		(exclude_from_sim no)
		(in_bom yes)
		(on_board yes)
		(dnp no)
		(fields_autoplaced yes)
		(property "Reference" "#PWR010"
			(at 194.31 200.66 0)
			(effects
				(font
					(size 1.27 1.27)
				)
				(justify left bottom)
				(hide yes)
			)
		)
		(property "Value" "GND"
			(at 194.31 199.39 0)
			(effects
				(font
					(size 1.27 1.27)
				)
			)
		)
		(property "Footprint" ""
			(at 185.42 201.93 0)
			(effects
				(font
					(size 1.27 1.27)
					(thickness 0.15)
				)
				(justify left bottom)
				(hide yes)
			)
		)
		(property "Datasheet" ""
			(at 185.42 207.01 0)
			(effects
				(font
					(size 1.27 1.27)
					(thickness 0.15)
				)
				(justify left bottom)
				(hide yes)
			)
		)
		(property "Description" ""
			(at 194.31 194.31 0)
			(effects
				(font
					(size 1.27 1.27)
				)
				(hide yes)
			)
		)
		(property "Author" "Antmicro"
			(at 185.42 201.93 0)
			(effects
				(font
					(size 1.27 1.27)
					(thickness 0.15)
				)
				(justify left bottom)
				(hide yes)
			)
		)
		(property "License" "Apache-2.0"
			(at 185.42 204.47 0)
			(effects
				(font
					(size 1.27 1.27)
					(thickness 0.15)
				)
				(justify left bottom)
				(hide yes)
			)
		)
		(pin "1"
		)
		(instances
			(project "cm4-baseboard"
				(path ""
					(reference "#PWR010")
					(unit 1)
				)
			)
			(project "usb"
				(path ""
					(reference "#PWR010")
					(unit 1)
				)
			)
		)
	)
	(symbol
		(lib_id "antmicroTestPoints:TP_0.75mm_SMD")
		(at 370.84 138.43 0)
		(mirror x)
		(unit 1)
		(exclude_from_sim no)
		(in_bom no)
		(on_board yes)
		(dnp no)
		(property "Reference" "TP918"
			(at 375.285 138.43 0)
			(effects
				(font
					(size 1.27 1.27)
				)
				(justify left)
			)
		)
		(property "Value" "TP_0.75mm_SMD"
			(at 370.84 135.89 0)
			(effects
				(font
					(size 1.27 1.27)
					(thickness 0.15)
				)
				(justify left bottom)
				(hide yes)
			)
		)
		(property "Footprint" "antmicro-footprints:TP_SMD_0.75mm"
			(at 375.92 143.51 0)
			(effects
				(font
					(size 1.27 1.27)
					(thickness 0.15)
				)
				(justify left bottom)
				(hide yes)
			)
		)
		(property "Datasheet" ""
			(at 375.92 146.05 0)
			(effects
				(font
					(size 1.27 1.27)
					(thickness 0.15)
				)
				(justify left bottom)
				(hide yes)
			)
		)
		(property "Description" ""
			(at 370.84 138.43 0)
			(effects
				(font
					(size 1.27 1.27)
				)
				(hide yes)
			)
		)
		(property "MPN" ""
			(at 370.84 138.43 0)
			(effects
				(font
					(size 1.27 1.27)
					(thickness 0.15)
				)
				(justify left bottom)
				(hide yes)
			)
		)
		(property "Manufacturer" ""
			(at 370.84 138.43 0)
			(effects
				(font
					(size 1.27 1.27)
					(thickness 0.15)
				)
				(justify left bottom)
				(hide yes)
			)
		)
		(property "Author" "Antmicro"
			(at 386.08 123.19 0)
			(effects
				(font
					(size 1.27 1.27)
					(thickness 0.15)
				)
				(justify left bottom)
				(hide yes)
			)
		)
		(property "License" "Apache-2.0"
			(at 386.08 120.65 0)
			(effects
				(font
					(size 1.27 1.27)
					(thickness 0.15)
				)
				(justify left bottom)
				(hide yes)
			)
		)
		(pin "1"
		)
		(instances
			(project "cm4-baseboard"
				(path ""
					(reference "TP918")
					(unit 1)
				)
			)
		)
	)
	(symbol
		(lib_id "antmicropower:GND")
		(at 167.64 214.63 0)
		(mirror y)
		(unit 1)
		(exclude_from_sim no)
		(in_bom yes)
		(on_board yes)
		(dnp no)
		(property "Reference" "#PWR013"
			(at 158.75 217.17 0)
			(effects
				(font
					(size 1.27 1.27)
					(thickness 0.15)
				)
				(justify left bottom)
				(hide yes)
			)
		)
		(property "Value" "GND"
			(at 167.64 218.44 0)
			(effects
				(font
					(size 1.27 1.27)
					(thickness 0.15)
				)
			)
		)
		(property "Footprint" ""
			(at 158.75 222.25 0)
			(effects
				(font
					(size 1.27 1.27)
					(thickness 0.15)
				)
				(justify left bottom)
				(hide yes)
			)
		)
		(property "Datasheet" ""
			(at 158.75 227.33 0)
			(effects
				(font
					(size 1.27 1.27)
					(thickness 0.15)
				)
				(justify left bottom)
				(hide yes)
			)
		)
		(property "Description" ""
			(at 167.64 214.63 0)
			(effects
				(font
					(size 1.27 1.27)
				)
				(hide yes)
			)
		)
		(property "Author" "Antmicro"
			(at 158.75 222.25 0)
			(effects
				(font
					(size 1.27 1.27)
					(thickness 0.15)
				)
				(justify left bottom)
				(hide yes)
			)
		)
		(property "License" "Apache-2.0"
			(at 158.75 224.79 0)
			(effects
				(font
					(size 1.27 1.27)
					(thickness 0.15)
				)
				(justify left bottom)
				(hide yes)
			)
		)
		(pin "1"
		)
		(instances
			(project "cm4-baseboard"
				(path ""
					(reference "#PWR013")
					(unit 1)
				)
			)
			(project "usb"
				(path ""
					(reference "#PWR013")
					(unit 1)
				)
			)
		)
	)
	(symbol
		(lib_id "antmicropower:GND")
		(at 130.81 208.28 0)
		(unit 1)
		(exclude_from_sim no)
		(in_bom yes)
		(on_board yes)
		(dnp no)
		(property "Reference" "#PWR0911"
			(at 130.81 214.63 0)
			(effects
				(font
					(size 1.27 1.27)
				)
				(justify left bottom)
				(hide yes)
			)
		)
		(property "Value" "GND"
			(at 130.81 212.09 0)
			(effects
				(font
					(size 1.27 1.27)
				)
			)
		)
		(property "Footprint" ""
			(at 130.81 208.28 0)
			(effects
				(font
					(size 1.27 1.27)
				)
				(hide yes)
			)
		)
		(property "Datasheet" ""
			(at 130.81 208.28 0)
			(effects
				(font
					(size 1.27 1.27)
				)
				(hide yes)
			)
		)
		(property "Description" ""
			(at 130.81 208.28 0)
			(effects
				(font
					(size 1.27 1.27)
				)
				(hide yes)
			)
		)
		(property "Author" "Antmicro"
			(at 139.7 215.9 0)
			(effects
				(font
					(size 1.27 1.27)
					(thickness 0.15)
				)
				(justify left bottom)
				(hide yes)
			)
		)
		(property "License" "Apache-2.0"
			(at 139.7 218.44 0)
			(effects
				(font
					(size 1.27 1.27)
					(thickness 0.15)
				)
				(justify left bottom)
				(hide yes)
			)
		)
		(pin "1"
		)
		(instances
			(project "cm4-baseboard"
				(path ""
					(reference "#PWR0911")
					(unit 1)
				)
			)
			(project "usb"
				(path ""
					(reference "#PWR0911")
					(unit 1)
				)
			)
		)
	)
	(symbol
		(lib_id "antmicropower:PWR_FLAG")
		(at 153.67 53.34 0)
		(unit 1)
		(exclude_from_sim no)
		(in_bom yes)
		(on_board yes)
		(dnp no)
		(property "Reference" "#FLG017"
			(at 153.67 51.435 0)
			(effects
				(font
					(size 1.27 1.27)
				)
				(hide yes)
			)
		)
		(property "Value" "PWR_FLAG"
			(at 153.67 49.53 0)
			(effects
				(font
					(size 1.27 1.27)
				)
			)
		)
		(property "Footprint" ""
			(at 153.67 53.34 0)
			(effects
				(font
					(size 1.27 1.27)
				)
				(hide yes)
			)
		)
		(property "Datasheet" ""
			(at 153.67 53.34 0)
			(effects
				(font
					(size 1.27 1.27)
				)
				(hide yes)
			)
		)
		(property "Description" ""
			(at 153.67 53.34 0)
			(effects
				(font
					(size 1.27 1.27)
				)
				(hide yes)
			)
		)
		(pin "1"
		)
		(instances
			(project "cm4-baseboard"
				(path ""
					(reference "#FLG017")
					(unit 1)
				)
			)
		)
	)
	(symbol
		(lib_id "antmicropower:GND")
		(at 128.27 273.05 0)
		(unit 1)
		(exclude_from_sim no)
		(in_bom yes)
		(on_board yes)
		(dnp no)
		(fields_autoplaced yes)
		(property "Reference" "#PWR04"
			(at 137.16 275.59 0)
			(effects
				(font
					(size 1.27 1.27)
					(thickness 0.15)
				)
				(justify left bottom)
				(hide yes)
			)
		)
		(property "Value" "GND"
			(at 128.27 279.4 0)
			(effects
				(font
					(size 1.27 1.27)
					(thickness 0.15)
				)
			)
		)
		(property "Footprint" ""
			(at 137.16 280.67 0)
			(effects
				(font
					(size 1.27 1.27)
					(thickness 0.15)
				)
				(justify left bottom)
				(hide yes)
			)
		)
		(property "Datasheet" ""
			(at 137.16 285.75 0)
			(effects
				(font
					(size 1.27 1.27)
					(thickness 0.15)
				)
				(justify left bottom)
				(hide yes)
			)
		)
		(property "Description" ""
			(at 128.27 273.05 0)
			(effects
				(font
					(size 1.27 1.27)
				)
				(hide yes)
			)
		)
		(property "Author" "Antmicro"
			(at 137.16 280.67 0)
			(effects
				(font
					(size 1.27 1.27)
					(thickness 0.15)
				)
				(justify left bottom)
				(hide yes)
			)
		)
		(property "License" "Apache-2.0"
			(at 137.16 283.21 0)
			(effects
				(font
					(size 1.27 1.27)
					(thickness 0.15)
				)
				(justify left bottom)
				(hide yes)
			)
		)
		(pin "1"
		)
		(instances
			(project "cm4-baseboard"
				(path ""
					(reference "#PWR04")
					(unit 1)
				)
			)
			(project "usb"
				(path ""
					(reference "#PWR04")
					(unit 1)
				)
			)
		)
	)
	(symbol
		(lib_id "antmicroCapacitors0402:C_4u7_0402")
		(at 297.18 44.45 90)
		(unit 1)
		(exclude_from_sim no)
		(in_bom yes)
		(on_board yes)
		(dnp no)
		(property "Reference" "C924"
			(at 297.815 40.005 90)
			(effects
				(font
					(size 1.27 1.27)
				)
				(justify right)
			)
		)
		(property "Value" "C_4u7_0402"
			(at 300.99 44.45 0)
			(effects
				(font
					(size 1.27 1.27)
					(thickness 0.15)
				)
				(justify left bottom)
				(hide yes)
			)
		)
		(property "Footprint" "antmicro-footprints:C_0402_1005Metric"
			(at 292.1 39.37 0)
			(effects
				(font
					(size 1.27 1.27)
					(thickness 0.15)
				)
				(justify left bottom)
				(hide yes)
			)
		)
		(property "Datasheet" "https://www.murata.com/products/productdetail?partno=GRM155R61A475MEAA%23"
			(at 297.18 44.45 0)
			(effects
				(font
					(size 1.27 1.27)
					(thickness 0.15)
				)
				(justify left bottom)
				(hide yes)
			)
		)
		(property "Description" ""
			(at 297.18 44.45 0)
			(effects
				(font
					(size 1.27 1.27)
				)
				(hide yes)
			)
		)
		(property "Manufacturer" "Murata"
			(at 287.02 39.37 0)
			(effects
				(font
					(size 1.27 1.27)
					(thickness 0.15)
				)
				(justify left bottom)
				(hide yes)
			)
		)
		(property "MPN" "GRM155R61A475MEAAD"
			(at 289.56 39.37 0)
			(effects
				(font
					(size 1.27 1.27)
					(thickness 0.15)
				)
				(justify left bottom)
				(hide yes)
			)
		)
		(property "Val" "4u7"
			(at 297.815 43.815 90)
			(effects
				(font
					(size 1.27 1.27)
					(thickness 0.15)
				)
				(justify right)
			)
		)
		(property "License" "Apache-2.0"
			(at 320.04 24.13 0)
			(effects
				(font
					(size 1.27 1.27)
					(thickness 0.15)
				)
				(justify left bottom)
				(hide yes)
			)
		)
		(property "Author" "Antmicro"
			(at 322.58 24.13 0)
			(effects
				(font
					(size 1.27 1.27)
					(thickness 0.15)
				)
				(justify left bottom)
				(hide yes)
			)
		)
		(property "Voltage" ""
			(at 325.12 24.13 0)
			(effects
				(font
					(size 1.27 1.27)
				)
				(justify left bottom)
				(hide yes)
			)
		)
		(property "Dielectric" ""
			(at 327.66 24.13 0)
			(effects
				(font
					(size 1.27 1.27)
				)
				(justify left bottom)
				(hide yes)
			)
		)
		(pin "1"
		)
		(pin "2"
		)
		(instances
			(project "cm4-baseboard"
				(path ""
					(reference "C924")
					(unit 1)
				)
			)
			(project "usb"
				(path ""
					(reference "C924")
					(unit 1)
				)
			)
		)
	)
	(symbol
		(lib_id "antmicroResistors0402:R_100k_0402")
		(at 71.12 129.54 270)
		(unit 1)
		(exclude_from_sim no)
		(in_bom yes)
		(on_board yes)
		(dnp no)
		(fields_autoplaced yes)
		(property "Reference" "R916"
			(at 68.58 130.81 90)
			(effects
				(font
					(size 1.27 1.27)
				)
				(justify right)
			)
		)
		(property "Value" "R_100k_0402"
			(at 67.31 129.54 0)
			(effects
				(font
					(size 1.27 1.27)
					(thickness 0.15)
				)
				(justify left bottom)
				(hide yes)
			)
		)
		(property "Footprint" "antmicro-footprints:R_0402_1005Metric"
			(at 76.2 134.62 0)
			(effects
				(font
					(size 1.27 1.27)
					(thickness 0.15)
				)
				(justify left bottom)
				(hide yes)
			)
		)
		(property "Datasheet" "https://www.bourns.com/docs/product-datasheets/cr.pdf"
			(at 71.12 129.54 0)
			(effects
				(font
					(size 1.27 1.27)
					(thickness 0.15)
				)
				(justify left bottom)
				(hide yes)
			)
		)
		(property "Description" ""
			(at 71.12 129.54 0)
			(effects
				(font
					(size 1.27 1.27)
				)
				(hide yes)
			)
		)
		(property "Manufacturer" "Bourns"
			(at 81.28 134.62 0)
			(effects
				(font
					(size 1.27 1.27)
					(thickness 0.15)
				)
				(justify left bottom)
				(hide yes)
			)
		)
		(property "MPN" "CR0402-FX-1003GLF"
			(at 78.74 134.62 0)
			(effects
				(font
					(size 1.27 1.27)
					(thickness 0.15)
				)
				(justify left bottom)
				(hide yes)
			)
		)
		(property "Val" "100k"
			(at 68.58 133.9849 90)
			(effects
				(font
					(size 1.27 1.27)
					(thickness 0.15)
				)
				(justify right)
			)
		)
		(property "License" "Apache-2.0"
			(at 45.72 149.86 0)
			(effects
				(font
					(size 1.27 1.27)
					(thickness 0.15)
				)
				(justify left bottom)
				(hide yes)
			)
		)
		(property "Author" "Antmicro"
			(at 43.18 149.86 0)
			(effects
				(font
					(size 1.27 1.27)
					(thickness 0.15)
				)
				(justify left bottom)
				(hide yes)
			)
		)
		(property "Tolerance" "1%"
			(at 60.96 149.86 0)
			(effects
				(font
					(size 1.27 1.27)
				)
				(justify left bottom)
				(hide yes)
			)
		)
		(pin "1"
		)
		(pin "2"
		)
		(instances
			(project "cm4-baseboard"
				(path ""
					(reference "R916")
					(unit 1)
				)
			)
			(project "usb"
				(path ""
					(reference "R916")
					(unit 1)
				)
			)
		)
	)
	(symbol
		(lib_id "antmicropower:GND")
		(at 39.37 97.79 0)
		(unit 1)
		(exclude_from_sim no)
		(in_bom yes)
		(on_board yes)
		(dnp no)
		(fields_autoplaced yes)
		(property "Reference" "#PWR0902"
			(at 48.26 100.33 0)
			(effects
				(font
					(size 1.27 1.27)
					(thickness 0.15)
				)
				(justify left bottom)
				(hide yes)
			)
		)
		(property "Value" "GND"
			(at 37.3598 102.87 0)
			(effects
				(font
					(size 1.27 1.27)
					(thickness 0.15)
				)
				(justify left bottom)
			)
		)
		(property "Footprint" ""
			(at 48.26 105.41 0)
			(effects
				(font
					(size 1.27 1.27)
					(thickness 0.15)
				)
				(justify left bottom)
				(hide yes)
			)
		)
		(property "Datasheet" ""
			(at 48.26 110.49 0)
			(effects
				(font
					(size 1.27 1.27)
					(thickness 0.15)
				)
				(justify left bottom)
				(hide yes)
			)
		)
		(property "Description" ""
			(at 39.37 97.79 0)
			(effects
				(font
					(size 1.27 1.27)
				)
				(hide yes)
			)
		)
		(property "Author" "Antmicro"
			(at 48.26 105.41 0)
			(effects
				(font
					(size 1.27 1.27)
					(thickness 0.15)
				)
				(justify left bottom)
				(hide yes)
			)
		)
		(property "License" "Apache-2.0"
			(at 48.26 107.95 0)
			(effects
				(font
					(size 1.27 1.27)
					(thickness 0.15)
				)
				(justify left bottom)
				(hide yes)
			)
		)
		(pin "1"
		)
		(instances
			(project "cm4-baseboard"
				(path ""
					(reference "#PWR0902")
					(unit 1)
				)
			)
			(project "usb"
				(path ""
					(reference "#PWR0902")
					(unit 1)
				)
			)
		)
	)
	(symbol
		(lib_id "antmicroResistors0402:R_470R_0402")
		(at 317.5 110.49 90)
		(unit 1)
		(exclude_from_sim no)
		(in_bom yes)
		(on_board yes)
		(dnp no)
		(fields_autoplaced yes)
		(property "Reference" "R920"
			(at 314.96 106.6799 90)
			(effects
				(font
					(size 1.27 1.27)
					(thickness 0.15)
				)
				(justify left)
			)
		)
		(property "Value" "R_470R_0402"
			(at 330.2 90.17 0)
			(effects
				(font
					(size 1.27 1.27)
					(thickness 0.15)
				)
				(justify left bottom)
				(hide yes)
			)
		)
		(property "Footprint" "antmicro-footprints:R_0402_1005Metric"
			(at 332.74 90.17 0)
			(effects
				(font
					(size 1.27 1.27)
					(thickness 0.15)
				)
				(justify left bottom)
				(hide yes)
			)
		)
		(property "Datasheet" "https://www.bourns.com/docs/product-datasheets/cr.pdf"
			(at 335.28 90.17 0)
			(effects
				(font
					(size 1.27 1.27)
					(thickness 0.15)
				)
				(justify left bottom)
				(hide yes)
			)
		)
		(property "Description" ""
			(at 317.5 110.49 0)
			(effects
				(font
					(size 1.27 1.27)
				)
				(hide yes)
			)
		)
		(property "Manufacturer" "Bourns"
			(at 340.36 90.17 0)
			(effects
				(font
					(size 1.27 1.27)
					(thickness 0.15)
				)
				(justify left bottom)
				(hide yes)
			)
		)
		(property "MPN" "CR0402-FX-4700GLF"
			(at 337.82 90.17 0)
			(effects
				(font
					(size 1.27 1.27)
					(thickness 0.15)
				)
				(justify left bottom)
				(hide yes)
			)
		)
		(property "Val" "470R"
			(at 314.96 109.2199 90)
			(effects
				(font
					(size 1.27 1.27)
					(thickness 0.15)
				)
				(justify left)
			)
		)
		(property "License" "Apache-2.0"
			(at 342.9 90.17 0)
			(effects
				(font
					(size 1.27 1.27)
					(thickness 0.15)
				)
				(justify left bottom)
				(hide yes)
			)
		)
		(property "Author" "Antmicro"
			(at 345.44 90.17 0)
			(effects
				(font
					(size 1.27 1.27)
					(thickness 0.15)
				)
				(justify left bottom)
				(hide yes)
			)
		)
		(property "Tolerance" "1%"
			(at 327.66 90.17 0)
			(effects
				(font
					(size 1.27 1.27)
				)
				(justify left bottom)
				(hide yes)
			)
		)
		(pin "1"
		)
		(pin "2"
		)
		(instances
			(project "cm4-baseboard"
				(path ""
					(reference "R920")
					(unit 1)
				)
			)
			(project "usb"
				(path ""
					(reference "R920")
					(unit 1)
				)
			)
		)
	)
	(symbol
		(lib_id "antmicroResistors0402:R_10k_0402")
		(at 168.91 66.04 270)
		(mirror x)
		(unit 1)
		(exclude_from_sim no)
		(in_bom yes)
		(on_board yes)
		(dnp no)
		(property "Reference" "R910"
			(at 167.64 63.5 90)
			(effects
				(font
					(size 1.27 1.27)
					(thickness 0.15)
				)
				(justify right top)
			)
		)
		(property "Value" "R_10k_0402"
			(at 156.21 45.72 0)
			(effects
				(font
					(size 1.27 1.27)
					(thickness 0.15)
				)
				(justify left bottom)
				(hide yes)
			)
		)
		(property "Footprint" "antmicro-footprints:R_0402_1005Metric"
			(at 153.67 45.72 0)
			(effects
				(font
					(size 1.27 1.27)
					(thickness 0.15)
				)
				(justify left bottom)
				(hide yes)
			)
		)
		(property "Datasheet" "https://www.bourns.com/docs/product-datasheets/cr.pdf"
			(at 151.13 45.72 0)
			(effects
				(font
					(size 1.27 1.27)
					(thickness 0.15)
				)
				(justify left bottom)
				(hide yes)
			)
		)
		(property "Description" ""
			(at 168.91 66.04 0)
			(effects
				(font
					(size 1.27 1.27)
				)
				(hide yes)
			)
		)
		(property "Manufacturer" "Bourns"
			(at 146.05 45.72 0)
			(effects
				(font
					(size 1.27 1.27)
					(thickness 0.15)
				)
				(justify left bottom)
				(hide yes)
			)
		)
		(property "MPN" "CR0402-FX-1002GLF"
			(at 148.59 45.72 0)
			(effects
				(font
					(size 1.27 1.27)
					(thickness 0.15)
				)
				(justify left bottom)
				(hide yes)
			)
		)
		(property "Val" "10k"
			(at 167.64 64.77 90)
			(effects
				(font
					(size 1.27 1.27)
					(thickness 0.15)
				)
				(justify right bottom)
			)
		)
		(property "License" "Apache-2.0"
			(at 143.51 45.72 0)
			(effects
				(font
					(size 1.27 1.27)
					(thickness 0.15)
				)
				(justify left bottom)
				(hide yes)
			)
		)
		(property "Author" "Antmicro"
			(at 140.97 45.72 0)
			(effects
				(font
					(size 1.27 1.27)
					(thickness 0.15)
				)
				(justify left bottom)
				(hide yes)
			)
		)
		(property "Tolerance" "1%"
			(at 158.75 45.72 0)
			(effects
				(font
					(size 1.27 1.27)
				)
				(justify left bottom)
				(hide yes)
			)
		)
		(pin "1"
		)
		(pin "2"
		)
		(instances
			(project "cm4-baseboard"
				(path ""
					(reference "R910")
					(unit 1)
				)
			)
			(project "usb"
				(path ""
					(reference "R910")
					(unit 1)
				)
			)
		)
	)
	(symbol
		(lib_id "antmicroResistors0402:R_10k_0402")
		(at 177.8 125.73 270)
		(unit 1)
		(exclude_from_sim no)
		(in_bom yes)
		(on_board yes)
		(dnp no)
		(property "Reference" "R906"
			(at 179.07 127.635 90)
			(effects
				(font
					(size 1.27 1.27)
				)
				(justify left)
			)
		)
		(property "Value" "R_10k_0402"
			(at 173.99 125.73 0)
			(effects
				(font
					(size 1.27 1.27)
					(thickness 0.15)
				)
				(justify left bottom)
				(hide yes)
			)
		)
		(property "Footprint" "antmicro-footprints:R_0402_1005Metric"
			(at 182.88 130.81 0)
			(effects
				(font
					(size 1.27 1.27)
					(thickness 0.15)
				)
				(justify left bottom)
				(hide yes)
			)
		)
		(property "Datasheet" "https://www.bourns.com/docs/product-datasheets/cr.pdf"
			(at 177.8 125.73 0)
			(effects
				(font
					(size 1.27 1.27)
					(thickness 0.15)
				)
				(justify left bottom)
				(hide yes)
			)
		)
		(property "Description" ""
			(at 177.8 125.73 0)
			(effects
				(font
					(size 1.27 1.27)
				)
				(hide yes)
			)
		)
		(property "Manufacturer" "Bourns"
			(at 187.96 130.81 0)
			(effects
				(font
					(size 1.27 1.27)
					(thickness 0.15)
				)
				(justify left bottom)
				(hide yes)
			)
		)
		(property "MPN" "CR0402-FX-1002GLF"
			(at 185.42 130.81 0)
			(effects
				(font
					(size 1.27 1.27)
					(thickness 0.15)
				)
				(justify left bottom)
				(hide yes)
			)
		)
		(property "Val" "10k"
			(at 179.07 129.5399 90)
			(effects
				(font
					(size 1.27 1.27)
					(thickness 0.15)
				)
				(justify left)
			)
		)
		(property "License" "Apache-2.0"
			(at 152.4 146.05 0)
			(effects
				(font
					(size 1.27 1.27)
					(thickness 0.15)
				)
				(justify left bottom)
				(hide yes)
			)
		)
		(property "Author" "Antmicro"
			(at 149.86 146.05 0)
			(effects
				(font
					(size 1.27 1.27)
					(thickness 0.15)
				)
				(justify left bottom)
				(hide yes)
			)
		)
		(property "Tolerance" "1%"
			(at 167.64 146.05 0)
			(effects
				(font
					(size 1.27 1.27)
				)
				(justify left bottom)
				(hide yes)
			)
		)
		(pin "1"
		)
		(pin "2"
		)
		(instances
			(project "cm4-baseboard"
				(path ""
					(reference "R906")
					(unit 1)
				)
			)
			(project "usb"
				(path ""
					(reference "R906")
					(unit 1)
				)
			)
		)
	)
	(symbol
		(lib_id "antmicroTestPoints:TP_0.75mm_SMD")
		(at 370.84 148.59 0)
		(mirror x)
		(unit 1)
		(exclude_from_sim no)
		(in_bom no)
		(on_board yes)
		(dnp no)
		(property "Reference" "TP917"
			(at 375.285 148.59 0)
			(effects
				(font
					(size 1.27 1.27)
				)
				(justify left)
			)
		)
		(property "Value" "TP_0.75mm_SMD"
			(at 370.84 146.05 0)
			(effects
				(font
					(size 1.27 1.27)
					(thickness 0.15)
				)
				(justify left bottom)
				(hide yes)
			)
		)
		(property "Footprint" "antmicro-footprints:TP_SMD_0.75mm"
			(at 375.92 153.67 0)
			(effects
				(font
					(size 1.27 1.27)
					(thickness 0.15)
				)
				(justify left bottom)
				(hide yes)
			)
		)
		(property "Datasheet" ""
			(at 375.92 156.21 0)
			(effects
				(font
					(size 1.27 1.27)
					(thickness 0.15)
				)
				(justify left bottom)
				(hide yes)
			)
		)
		(property "Description" ""
			(at 370.84 148.59 0)
			(effects
				(font
					(size 1.27 1.27)
				)
				(hide yes)
			)
		)
		(property "MPN" ""
			(at 370.84 148.59 0)
			(effects
				(font
					(size 1.27 1.27)
					(thickness 0.15)
				)
				(justify left bottom)
				(hide yes)
			)
		)
		(property "Manufacturer" ""
			(at 370.84 148.59 0)
			(effects
				(font
					(size 1.27 1.27)
					(thickness 0.15)
				)
				(justify left bottom)
				(hide yes)
			)
		)
		(property "Author" "Antmicro"
			(at 386.08 133.35 0)
			(effects
				(font
					(size 1.27 1.27)
					(thickness 0.15)
				)
				(justify left bottom)
				(hide yes)
			)
		)
		(property "License" "Apache-2.0"
			(at 386.08 130.81 0)
			(effects
				(font
					(size 1.27 1.27)
					(thickness 0.15)
				)
				(justify left bottom)
				(hide yes)
			)
		)
		(pin "1"
		)
		(instances
			(project "cm4-baseboard"
				(path ""
					(reference "TP917")
					(unit 1)
				)
			)
			(project "usb"
				(path ""
					(reference "TP917")
					(unit 1)
				)
			)
		)
	)
	(symbol
		(lib_id "antmicroCapacitors0402:C_100n_0402")
		(at 384.81 205.74 90)
		(unit 1)
		(exclude_from_sim no)
		(in_bom yes)
		(on_board yes)
		(dnp no)
		(property "Reference" "C936"
			(at 386.08 200.66 90)
			(effects
				(font
					(size 1.27 1.27)
					(thickness 0.15)
				)
				(justify right)
			)
		)
		(property "Value" "C_100n_0402"
			(at 394.97 185.42 0)
			(effects
				(font
					(size 1.27 1.27)
					(thickness 0.15)
				)
				(justify left bottom)
				(hide yes)
			)
		)
		(property "Footprint" "antmicro-footprints:C_0402_1005Metric"
			(at 397.51 185.42 0)
			(effects
				(font
					(size 1.27 1.27)
					(thickness 0.15)
				)
				(justify left bottom)
				(hide yes)
			)
		)
		(property "Datasheet" "https://www.murata.com/products/productdetail?partno=GRM155R61H104KE14%23"
			(at 400.05 185.42 0)
			(effects
				(font
					(size 1.27 1.27)
					(thickness 0.15)
				)
				(justify left bottom)
				(hide yes)
			)
		)
		(property "Description" ""
			(at 384.81 205.74 0)
			(effects
				(font
					(size 1.27 1.27)
				)
				(hide yes)
			)
		)
		(property "MPN" "GRM155R61H104KE14D"
			(at 402.59 185.42 0)
			(effects
				(font
					(size 1.27 1.27)
					(thickness 0.15)
				)
				(justify left bottom)
				(hide yes)
			)
		)
		(property "Manufacturer" "Murata"
			(at 405.13 185.42 0)
			(effects
				(font
					(size 1.27 1.27)
					(thickness 0.15)
				)
				(justify left bottom)
				(hide yes)
			)
		)
		(property "License" "Apache-2.0"
			(at 407.67 185.42 0)
			(effects
				(font
					(size 1.27 1.27)
					(thickness 0.15)
				)
				(justify left bottom)
				(hide yes)
			)
		)
		(property "Author" "Antmicro"
			(at 410.21 185.42 0)
			(effects
				(font
					(size 1.27 1.27)
					(thickness 0.15)
				)
				(justify left bottom)
				(hide yes)
			)
		)
		(property "Val" "100n"
			(at 386.08 205.74 90)
			(effects
				(font
					(size 1.27 1.27)
					(thickness 0.15)
				)
				(justify right)
			)
		)
		(property "Voltage" "50V"
			(at 412.75 185.42 0)
			(effects
				(font
					(size 1.27 1.27)
				)
				(justify left bottom)
				(hide yes)
			)
		)
		(property "Dielectric" "X5R"
			(at 415.29 185.42 0)
			(effects
				(font
					(size 1.27 1.27)
				)
				(justify left bottom)
				(hide yes)
			)
		)
		(pin "1"
		)
		(pin "2"
		)
		(instances
			(project "cm4-baseboard"
				(path ""
					(reference "C936")
					(unit 1)
				)
			)
		)
	)
	(symbol
		(lib_id "antmicroCapacitorsmisc:C_22u_25V_0805")
		(at 234.95 60.96 90)
		(mirror x)
		(unit 1)
		(exclude_from_sim no)
		(in_bom yes)
		(on_board yes)
		(dnp no)
		(property "Reference" "C911"
			(at 237.49 60.96 90)
			(effects
				(font
					(size 1.27 1.27)
				)
				(justify right)
			)
		)
		(property "Value" "C_22u_25V_0805"
			(at 238.76 60.96 0)
			(effects
				(font
					(size 1.27 1.27)
				)
				(justify left bottom)
				(hide yes)
			)
		)
		(property "Footprint" "antmicro-footprints:C_0805_2012Metric"
			(at 229.87 66.04 0)
			(effects
				(font
					(size 1.524 1.524)
				)
				(justify left bottom)
				(hide yes)
			)
		)
		(property "Datasheet" "https://product.samsungsem.com/mlcc/CL21A226MAYNNN.do"
			(at 234.95 60.96 0)
			(effects
				(font
					(size 1.27 1.27)
				)
				(justify left bottom)
				(hide yes)
			)
		)
		(property "Description" ""
			(at 234.95 60.96 0)
			(effects
				(font
					(size 1.27 1.27)
				)
				(hide yes)
			)
		)
		(property "Manufacturer" "Samsung Electro-Mechanics"
			(at 224.79 66.04 0)
			(effects
				(font
					(size 1.524 1.524)
				)
				(justify left bottom)
				(hide yes)
			)
		)
		(property "MPN" "CL21A226MAYNNNE"
			(at 227.33 66.04 0)
			(effects
				(font
					(size 1.524 1.524)
				)
				(justify left bottom)
				(hide yes)
			)
		)
		(property "Val" "22u"
			(at 237.49 63.5 90)
			(effects
				(font
					(size 1.27 1.27)
				)
				(justify right)
			)
		)
		(property "License" "Apache-2.0"
			(at 257.81 81.28 0)
			(effects
				(font
					(size 1.27 1.27)
					(thickness 0.15)
				)
				(justify left bottom)
				(hide yes)
			)
		)
		(property "Author" "Antmicro"
			(at 260.35 81.28 0)
			(effects
				(font
					(size 1.27 1.27)
					(thickness 0.15)
				)
				(justify left bottom)
				(hide yes)
			)
		)
		(property "Voltage" "25V"
			(at 237.49 66.04 90)
			(effects
				(font
					(size 1.27 1.27)
				)
				(justify right)
			)
		)
		(property "Dielectric" "X5R"
			(at 265.43 81.28 0)
			(effects
				(font
					(size 1.27 1.27)
				)
				(justify left bottom)
				(hide yes)
			)
		)
		(property "Public" "False"
			(at 267.97 81.28 0)
			(effects
				(font
					(size 1.27 1.27)
				)
				(justify left bottom)
				(hide yes)
			)
		)
		(pin "1"
		)
		(pin "2"
		)
		(instances
			(project "cm4-baseboard"
				(path ""
					(reference "C911")
					(unit 1)
				)
			)
		)
	)
	(symbol
		(lib_id "antmicroResistors0402:R_470k_0402")
		(at 168.91 250.19 270)
		(mirror x)
		(unit 1)
		(exclude_from_sim no)
		(in_bom yes)
		(on_board yes)
		(dnp no)
		(property "Reference" "R915"
			(at 167.64 245.11 90)
			(effects
				(font
					(size 1.27 1.27)
					(thickness 0.15)
				)
				(justify right)
			)
		)
		(property "Value" "R_470k_0402"
			(at 156.21 229.87 0)
			(effects
				(font
					(size 1.27 1.27)
					(thickness 0.15)
				)
				(justify left bottom)
				(hide yes)
			)
		)
		(property "Footprint" "antmicro-footprints:R_0402_1005Metric"
			(at 153.67 229.87 0)
			(effects
				(font
					(size 1.27 1.27)
					(thickness 0.15)
				)
				(justify left bottom)
				(hide yes)
			)
		)
		(property "Datasheet" "https://www.bourns.com/docs/product-datasheets/cr.pdf"
			(at 151.13 229.87 0)
			(effects
				(font
					(size 1.27 1.27)
					(thickness 0.15)
				)
				(justify left bottom)
				(hide yes)
			)
		)
		(property "Description" ""
			(at 168.91 250.19 0)
			(effects
				(font
					(size 1.27 1.27)
				)
				(hide yes)
			)
		)
		(property "MPN" "CR0402-FX-4703GLF"
			(at 148.59 229.87 0)
			(effects
				(font
					(size 1.27 1.27)
					(thickness 0.15)
				)
				(justify left bottom)
				(hide yes)
			)
		)
		(property "Manufacturer" "Bourns"
			(at 146.05 229.87 0)
			(effects
				(font
					(size 1.27 1.27)
					(thickness 0.15)
				)
				(justify left bottom)
				(hide yes)
			)
		)
		(property "License" "Apache-2.0"
			(at 143.51 229.87 0)
			(effects
				(font
					(size 1.27 1.27)
					(thickness 0.15)
				)
				(justify left bottom)
				(hide yes)
			)
		)
		(property "Author" "Antmicro"
			(at 140.97 229.87 0)
			(effects
				(font
					(size 1.27 1.27)
					(thickness 0.15)
				)
				(justify left bottom)
				(hide yes)
			)
		)
		(property "Val" "470k"
			(at 167.64 247.65 90)
			(effects
				(font
					(size 1.27 1.27)
					(thickness 0.15)
				)
				(justify right)
			)
		)
		(property "Tolerance" "1%"
			(at 158.75 229.87 0)
			(effects
				(font
					(size 1.27 1.27)
				)
				(justify left bottom)
				(hide yes)
			)
		)
		(pin "1"
		)
		(pin "2"
		)
		(instances
			(project "cm4-baseboard"
				(path ""
					(reference "R915")
					(unit 1)
				)
			)
			(project "usb"
				(path ""
					(reference "R915")
					(unit 1)
				)
			)
		)
	)
	(symbol
		(lib_id "antmicroResistors0402:R_15k_0402")
		(at 71.12 144.78 90)
		(unit 1)
		(exclude_from_sim no)
		(in_bom yes)
		(on_board yes)
		(dnp no)
		(fields_autoplaced yes)
		(property "Reference" "R917"
			(at 68.58 140.9699 90)
			(effects
				(font
					(size 1.27 1.27)
				)
				(justify left)
			)
		)
		(property "Value" "R_15k_0402"
			(at 78.74 144.78 0)
			(effects
				(font
					(size 1.27 1.27)
				)
				(justify left bottom)
				(hide yes)
			)
		)
		(property "Footprint" "antmicro-footprints:R_0402_1005Metric"
			(at 66.04 139.7 0)
			(effects
				(font
					(size 1.524 1.524)
				)
				(justify left bottom)
				(hide yes)
			)
		)
		(property "Datasheet" "https://www.bourns.com/docs/product-datasheets/cr.pdf"
			(at 76.2 144.78 0)
			(effects
				(font
					(size 1.27 1.27)
				)
				(justify left bottom)
				(hide yes)
			)
		)
		(property "Description" ""
			(at 71.12 144.78 0)
			(effects
				(font
					(size 1.27 1.27)
				)
				(hide yes)
			)
		)
		(property "Manufacturer" "Bourns"
			(at 60.96 139.7 0)
			(effects
				(font
					(size 1.524 1.524)
				)
				(justify left bottom)
				(hide yes)
			)
		)
		(property "MPN" "CR0402-FX-1502GLF"
			(at 63.5 139.7 0)
			(effects
				(font
					(size 1.524 1.524)
				)
				(justify left bottom)
				(hide yes)
			)
		)
		(property "Val" "15k"
			(at 68.58 143.5099 90)
			(effects
				(font
					(size 1.27 1.27)
				)
				(justify left)
			)
		)
		(property "License" "Apache-2.0"
			(at 96.52 124.46 0)
			(effects
				(font
					(size 1.27 1.27)
					(thickness 0.15)
				)
				(justify left bottom)
				(hide yes)
			)
		)
		(property "Author" "Antmicro"
			(at 99.06 124.46 0)
			(effects
				(font
					(size 1.27 1.27)
					(thickness 0.15)
				)
				(justify left bottom)
				(hide yes)
			)
		)
		(property "Tolerance" "1%"
			(at 81.28 124.46 0)
			(effects
				(font
					(size 1.27 1.27)
				)
				(justify left bottom)
				(hide yes)
			)
		)
		(pin "1"
		)
		(pin "2"
		)
		(instances
			(project "cm4-baseboard"
				(path ""
					(reference "R917")
					(unit 1)
				)
			)
			(project "usb"
				(path ""
					(reference "R917")
					(unit 1)
				)
			)
		)
	)
	(symbol
		(lib_id "antmicropower:GND")
		(at 92.71 207.01 0)
		(unit 1)
		(exclude_from_sim no)
		(in_bom yes)
		(on_board yes)
		(dnp no)
		(fields_autoplaced yes)
		(property "Reference" "#PWR011"
			(at 101.6 209.55 0)
			(effects
				(font
					(size 1.27 1.27)
					(thickness 0.15)
				)
				(justify left bottom)
				(hide yes)
			)
		)
		(property "Value" "GND"
			(at 90.6998 212.09 0)
			(effects
				(font
					(size 1.27 1.27)
					(thickness 0.15)
				)
				(justify left bottom)
			)
		)
		(property "Footprint" ""
			(at 101.6 214.63 0)
			(effects
				(font
					(size 1.27 1.27)
					(thickness 0.15)
				)
				(justify left bottom)
				(hide yes)
			)
		)
		(property "Datasheet" ""
			(at 101.6 219.71 0)
			(effects
				(font
					(size 1.27 1.27)
					(thickness 0.15)
				)
				(justify left bottom)
				(hide yes)
			)
		)
		(property "Description" ""
			(at 92.71 207.01 0)
			(effects
				(font
					(size 1.27 1.27)
				)
				(hide yes)
			)
		)
		(property "Author" "Antmicro"
			(at 101.6 214.63 0)
			(effects
				(font
					(size 1.27 1.27)
					(thickness 0.15)
				)
				(justify left bottom)
				(hide yes)
			)
		)
		(property "License" "Apache-2.0"
			(at 101.6 217.17 0)
			(effects
				(font
					(size 1.27 1.27)
					(thickness 0.15)
				)
				(justify left bottom)
				(hide yes)
			)
		)
		(pin "1"
		)
		(instances
			(project "cm4-baseboard"
				(path ""
					(reference "#PWR011")
					(unit 1)
				)
			)
			(project "usb"
				(path ""
					(reference "#PWR011")
					(unit 1)
				)
			)
		)
	)
	(symbol
		(lib_id "antmicropower:GND")
		(at 120.65 78.74 0)
		(mirror y)
		(unit 1)
		(exclude_from_sim no)
		(in_bom yes)
		(on_board yes)
		(dnp no)
		(fields_autoplaced yes)
		(property "Reference" "#PWR0913"
			(at 111.76 81.28 0)
			(effects
				(font
					(size 1.27 1.27)
					(thickness 0.15)
				)
				(justify left bottom)
				(hide yes)
			)
		)
		(property "Value" "GND"
			(at 122.6602 83.82 0)
			(effects
				(font
					(size 1.27 1.27)
					(thickness 0.15)
				)
				(justify left bottom)
			)
		)
		(property "Footprint" ""
			(at 111.76 86.36 0)
			(effects
				(font
					(size 1.27 1.27)
					(thickness 0.15)
				)
				(justify left bottom)
				(hide yes)
			)
		)
		(property "Datasheet" ""
			(at 111.76 91.44 0)
			(effects
				(font
					(size 1.27 1.27)
					(thickness 0.15)
				)
				(justify left bottom)
				(hide yes)
			)
		)
		(property "Description" ""
			(at 120.65 78.74 0)
			(effects
				(font
					(size 1.27 1.27)
				)
				(hide yes)
			)
		)
		(property "Author" "Antmicro"
			(at 111.76 86.36 0)
			(effects
				(font
					(size 1.27 1.27)
					(thickness 0.15)
				)
				(justify left bottom)
				(hide yes)
			)
		)
		(property "License" "Apache-2.0"
			(at 111.76 88.9 0)
			(effects
				(font
					(size 1.27 1.27)
					(thickness 0.15)
				)
				(justify left bottom)
				(hide yes)
			)
		)
		(pin "1"
		)
		(instances
			(project "cm4-baseboard"
				(path ""
					(reference "#PWR0913")
					(unit 1)
				)
			)
			(project "usb"
				(path ""
					(reference "#PWR0913")
					(unit 1)
				)
			)
		)
	)
	(symbol
		(lib_id "antmicropower:GND")
		(at 281.94 30.48 0)
		(unit 1)
		(exclude_from_sim no)
		(in_bom yes)
		(on_board yes)
		(dnp no)
		(property "Reference" "#PWR0940"
			(at 281.94 36.83 0)
			(effects
				(font
					(size 1.27 1.27)
				)
				(hide yes)
			)
		)
		(property "Value" "GND"
			(at 281.94 34.29 0)
			(effects
				(font
					(size 1.27 1.27)
				)
			)
		)
		(property "Footprint" ""
			(at 290.83 38.1 0)
			(effects
				(font
					(size 1.27 1.27)
					(thickness 0.15)
				)
				(justify left bottom)
				(hide yes)
			)
		)
		(property "Datasheet" ""
			(at 290.83 43.18 0)
			(effects
				(font
					(size 1.27 1.27)
					(thickness 0.15)
				)
				(justify left bottom)
				(hide yes)
			)
		)
		(property "Description" ""
			(at 281.94 30.48 0)
			(effects
				(font
					(size 1.27 1.27)
				)
				(hide yes)
			)
		)
		(property "Author" "Antmicro"
			(at 290.83 38.1 0)
			(effects
				(font
					(size 1.27 1.27)
					(thickness 0.15)
				)
				(justify left bottom)
				(hide yes)
			)
		)
		(property "License" "Apache-2.0"
			(at 290.83 40.64 0)
			(effects
				(font
					(size 1.27 1.27)
					(thickness 0.15)
				)
				(justify left bottom)
				(hide yes)
			)
		)
		(pin "1"
		)
		(instances
			(project "cm4-baseboard"
				(path ""
					(reference "#PWR0940")
					(unit 1)
				)
			)
			(project "usb"
				(path ""
					(reference "#PWR0940")
					(unit 1)
				)
			)
		)
	)
	(symbol
		(lib_id "antmicroResistors0402:R_2k2_0402")
		(at 182.88 140.97 0)
		(unit 1)
		(exclude_from_sim no)
		(in_bom yes)
		(on_board yes)
		(dnp no)
		(property "Reference" "R907"
			(at 185.42 143.51 0)
			(effects
				(font
					(size 1.27 1.27)
				)
			)
		)
		(property "Value" "R_2k2_0402"
			(at 182.88 144.78 0)
			(effects
				(font
					(size 1.27 1.27)
					(thickness 0.15)
				)
				(justify left bottom)
				(hide yes)
			)
		)
		(property "Footprint" "antmicro-footprints:R_0402_1005Metric"
			(at 187.96 135.89 0)
			(effects
				(font
					(size 1.27 1.27)
					(thickness 0.15)
				)
				(justify left bottom)
				(hide yes)
			)
		)
		(property "Datasheet" "https://www.bourns.com/docs/product-datasheets/cr.pdf"
			(at 182.88 140.97 0)
			(effects
				(font
					(size 1.27 1.27)
					(thickness 0.15)
				)
				(justify left bottom)
				(hide yes)
			)
		)
		(property "Description" ""
			(at 182.88 140.97 0)
			(effects
				(font
					(size 1.27 1.27)
				)
				(hide yes)
			)
		)
		(property "Manufacturer" "Bourns"
			(at 187.96 130.81 0)
			(effects
				(font
					(size 1.27 1.27)
					(thickness 0.15)
				)
				(justify left bottom)
				(hide yes)
			)
		)
		(property "MPN" "CR0402-FX-2201GLF"
			(at 187.96 133.35 0)
			(effects
				(font
					(size 1.27 1.27)
					(thickness 0.15)
				)
				(justify left bottom)
				(hide yes)
			)
		)
		(property "Val" "2k2"
			(at 185.42 146.05 0)
			(effects
				(font
					(size 1.27 1.27)
					(thickness 0.15)
				)
			)
		)
		(property "License" "Apache-2.0"
			(at 203.2 166.37 0)
			(effects
				(font
					(size 1.27 1.27)
					(thickness 0.15)
				)
				(justify left bottom)
				(hide yes)
			)
		)
		(property "Author" "Antmicro"
			(at 203.2 168.91 0)
			(effects
				(font
					(size 1.27 1.27)
					(thickness 0.15)
				)
				(justify left bottom)
				(hide yes)
			)
		)
		(property "Tolerance" "1%"
			(at 203.2 151.13 0)
			(effects
				(font
					(size 1.27 1.27)
				)
				(justify left bottom)
				(hide yes)
			)
		)
		(pin "1"
		)
		(pin "2"
		)
		(instances
			(project "cm4-baseboard"
				(path ""
					(reference "R907")
					(unit 1)
				)
			)
			(project "usb"
				(path ""
					(reference "R907")
					(unit 1)
				)
			)
		)
	)
	(symbol
		(lib_id "antmicroCapacitors0402:C_100n_0402")
		(at 281.94 24.13 270)
		(unit 1)
		(exclude_from_sim no)
		(in_bom yes)
		(on_board yes)
		(dnp no)
		(fields_autoplaced yes)
		(property "Reference" "C917"
			(at 284.48 25.4063 90)
			(effects
				(font
					(size 1.27 1.27)
				)
				(justify left)
			)
		)
		(property "Value" "C_100n_0402"
			(at 278.13 24.13 0)
			(effects
				(font
					(size 1.27 1.27)
					(thickness 0.15)
				)
				(justify left bottom)
				(hide yes)
			)
		)
		(property "Footprint" "antmicro-footprints:C_0402_1005Metric"
			(at 287.02 29.21 0)
			(effects
				(font
					(size 1.27 1.27)
					(thickness 0.15)
				)
				(justify left bottom)
				(hide yes)
			)
		)
		(property "Datasheet" "https://www.murata.com/products/productdetail?partno=GRM155R61H104KE14%23"
			(at 281.94 24.13 0)
			(effects
				(font
					(size 1.27 1.27)
					(thickness 0.15)
				)
				(justify left bottom)
				(hide yes)
			)
		)
		(property "Description" ""
			(at 281.94 24.13 0)
			(effects
				(font
					(size 1.27 1.27)
				)
				(hide yes)
			)
		)
		(property "Manufacturer" "Murata"
			(at 292.1 29.21 0)
			(effects
				(font
					(size 1.27 1.27)
					(thickness 0.15)
				)
				(justify left bottom)
				(hide yes)
			)
		)
		(property "MPN" "GRM155R61H104KE14D"
			(at 289.56 29.21 0)
			(effects
				(font
					(size 1.27 1.27)
					(thickness 0.15)
				)
				(justify left bottom)
				(hide yes)
			)
		)
		(property "Val" "100n"
			(at 284.48 28.5812 90)
			(effects
				(font
					(size 1.27 1.27)
					(thickness 0.15)
				)
				(justify left)
			)
		)
		(property "License" "Apache-2.0"
			(at 259.08 44.45 0)
			(effects
				(font
					(size 1.27 1.27)
					(thickness 0.15)
				)
				(justify left bottom)
				(hide yes)
			)
		)
		(property "Author" "Antmicro"
			(at 256.54 44.45 0)
			(effects
				(font
					(size 1.27 1.27)
					(thickness 0.15)
				)
				(justify left bottom)
				(hide yes)
			)
		)
		(property "Voltage" "50V"
			(at 254 44.45 0)
			(effects
				(font
					(size 1.27 1.27)
				)
				(justify left bottom)
				(hide yes)
			)
		)
		(property "Dielectric" "X5R"
			(at 251.46 44.45 0)
			(effects
				(font
					(size 1.27 1.27)
				)
				(justify left bottom)
				(hide yes)
			)
		)
		(pin "1"
		)
		(pin "2"
		)
		(instances
			(project "cm4-baseboard"
				(path ""
					(reference "C917")
					(unit 1)
				)
			)
			(project "usb"
				(path ""
					(reference "C917")
					(unit 1)
				)
			)
		)
	)
	(symbol
		(lib_id "antmicropower:PWR_FLAG")
		(at 297.18 68.58 0)
		(unit 1)
		(exclude_from_sim no)
		(in_bom yes)
		(on_board yes)
		(dnp no)
		(property "Reference" "#FLG011"
			(at 297.18 66.675 0)
			(effects
				(font
					(size 1.27 1.27)
				)
				(hide yes)
			)
		)
		(property "Value" "PWR_FLAG"
			(at 297.18 64.77 0)
			(effects
				(font
					(size 1.27 1.27)
				)
			)
		)
		(property "Footprint" ""
			(at 297.18 68.58 0)
			(effects
				(font
					(size 1.27 1.27)
				)
				(hide yes)
			)
		)
		(property "Datasheet" ""
			(at 297.18 68.58 0)
			(effects
				(font
					(size 1.27 1.27)
				)
				(hide yes)
			)
		)
		(property "Description" ""
			(at 297.18 68.58 0)
			(effects
				(font
					(size 1.27 1.27)
				)
				(hide yes)
			)
		)
		(pin "1"
		)
		(instances
			(project "cm4-baseboard"
				(path ""
					(reference "#FLG011")
					(unit 1)
				)
			)
		)
	)
	(symbol
		(lib_id "antmicroTestPoints:TP_0.75mm_SMD")
		(at 370.84 140.97 0)
		(mirror x)
		(unit 1)
		(exclude_from_sim no)
		(in_bom no)
		(on_board yes)
		(dnp no)
		(property "Reference" "TP919"
			(at 375.285 140.97 0)
			(effects
				(font
					(size 1.27 1.27)
				)
				(justify left)
			)
		)
		(property "Value" "TP_0.75mm_SMD"
			(at 370.84 138.43 0)
			(effects
				(font
					(size 1.27 1.27)
					(thickness 0.15)
				)
				(justify left bottom)
				(hide yes)
			)
		)
		(property "Footprint" "antmicro-footprints:TP_SMD_0.75mm"
			(at 375.92 146.05 0)
			(effects
				(font
					(size 1.27 1.27)
					(thickness 0.15)
				)
				(justify left bottom)
				(hide yes)
			)
		)
		(property "Datasheet" ""
			(at 375.92 148.59 0)
			(effects
				(font
					(size 1.27 1.27)
					(thickness 0.15)
				)
				(justify left bottom)
				(hide yes)
			)
		)
		(property "Description" ""
			(at 370.84 140.97 0)
			(effects
				(font
					(size 1.27 1.27)
				)
				(hide yes)
			)
		)
		(property "MPN" ""
			(at 370.84 140.97 0)
			(effects
				(font
					(size 1.27 1.27)
					(thickness 0.15)
				)
				(justify left bottom)
				(hide yes)
			)
		)
		(property "Manufacturer" ""
			(at 370.84 140.97 0)
			(effects
				(font
					(size 1.27 1.27)
					(thickness 0.15)
				)
				(justify left bottom)
				(hide yes)
			)
		)
		(property "Author" "Antmicro"
			(at 386.08 125.73 0)
			(effects
				(font
					(size 1.27 1.27)
					(thickness 0.15)
				)
				(justify left bottom)
				(hide yes)
			)
		)
		(property "License" "Apache-2.0"
			(at 386.08 123.19 0)
			(effects
				(font
					(size 1.27 1.27)
					(thickness 0.15)
				)
				(justify left bottom)
				(hide yes)
			)
		)
		(pin "1"
		)
		(instances
			(project "cm4-baseboard"
				(path ""
					(reference "TP919")
					(unit 1)
				)
			)
		)
	)
	(symbol
		(lib_id "antmicropower:GND")
		(at 281.94 62.23 0)
		(unit 1)
		(exclude_from_sim no)
		(in_bom yes)
		(on_board yes)
		(dnp no)
		(property "Reference" "#PWR0942"
			(at 281.94 68.58 0)
			(effects
				(font
					(size 1.27 1.27)
				)
				(hide yes)
			)
		)
		(property "Value" "GND"
			(at 281.94 66.04 0)
			(effects
				(font
					(size 1.27 1.27)
				)
			)
		)
		(property "Footprint" ""
			(at 290.83 69.85 0)
			(effects
				(font
					(size 1.27 1.27)
					(thickness 0.15)
				)
				(justify left bottom)
				(hide yes)
			)
		)
		(property "Datasheet" ""
			(at 290.83 74.93 0)
			(effects
				(font
					(size 1.27 1.27)
					(thickness 0.15)
				)
				(justify left bottom)
				(hide yes)
			)
		)
		(property "Description" ""
			(at 281.94 62.23 0)
			(effects
				(font
					(size 1.27 1.27)
				)
				(hide yes)
			)
		)
		(property "Author" "Antmicro"
			(at 290.83 69.85 0)
			(effects
				(font
					(size 1.27 1.27)
					(thickness 0.15)
				)
				(justify left bottom)
				(hide yes)
			)
		)
		(property "License" "Apache-2.0"
			(at 290.83 72.39 0)
			(effects
				(font
					(size 1.27 1.27)
					(thickness 0.15)
				)
				(justify left bottom)
				(hide yes)
			)
		)
		(pin "1"
		)
		(instances
			(project "cm4-baseboard"
				(path ""
					(reference "#PWR0942")
					(unit 1)
				)
			)
			(project "usb"
				(path ""
					(reference "#PWR0942")
					(unit 1)
				)
			)
		)
	)
	(symbol
		(lib_id "antmicroLEDIndicationDiscrete:LED_G_0603_KP-1608CGCK")
		(at 102.87 76.2 270)
		(mirror x)
		(unit 1)
		(exclude_from_sim no)
		(in_bom yes)
		(on_board yes)
		(dnp no)
		(property "Reference" "D906"
			(at 99.06 72.39 90)
			(effects
				(font
					(size 1.27 1.27)
					(thickness 0.15)
				)
			)
		)
		(property "Value" "LED_G_0603_KP-1608CGCK"
			(at 95.25 53.34 0)
			(effects
				(font
					(size 1.27 1.27)
					(thickness 0.15)
				)
				(justify left bottom)
				(hide yes)
			)
		)
		(property "Footprint" "antmicro-footprints:LED_0603_1608Metric_G"
			(at 92.71 53.34 0)
			(effects
				(font
					(size 1.27 1.27)
					(thickness 0.15)
				)
				(justify left bottom)
				(hide yes)
			)
		)
		(property "Datasheet" "http://www.kingbright.com/attachments/file/psearch//000/00/00/KP-1608CGCK(Ver.23B).pdf"
			(at 90.17 53.34 0)
			(effects
				(font
					(size 1.27 1.27)
					(thickness 0.15)
				)
				(justify left bottom)
				(hide yes)
			)
		)
		(property "Description" ""
			(at 102.87 76.2 0)
			(effects
				(font
					(size 1.27 1.27)
				)
				(hide yes)
			)
		)
		(property "MPN" "KP-1608CGCK"
			(at 87.63 53.34 0)
			(effects
				(font
					(size 1.27 1.27)
					(thickness 0.15)
				)
				(justify left bottom)
				(hide yes)
			)
		)
		(property "Manufacturer" "Kingbright"
			(at 85.09 53.34 0)
			(effects
				(font
					(size 1.27 1.27)
					(thickness 0.15)
				)
				(justify left bottom)
				(hide yes)
			)
		)
		(property "Color" "Green"
			(at 99.06 74.93 90)
			(effects
				(font
					(size 1.27 1.27)
				)
			)
		)
		(property "Author" "Antmicro"
			(at 82.55 53.34 0)
			(effects
				(font
					(size 1.27 1.27)
					(thickness 0.15)
				)
				(justify left bottom)
				(hide yes)
			)
		)
		(property "License" "Apache-2.0"
			(at 80.01 53.34 0)
			(effects
				(font
					(size 1.27 1.27)
					(thickness 0.15)
				)
				(justify left bottom)
				(hide yes)
			)
		)
		(pin "2"
		)
		(pin "1"
		)
		(instances
			(project "cm4-baseboard"
				(path ""
					(reference "D906")
					(unit 1)
				)
			)
		)
	)
	(symbol
		(lib_id "antmicroResistors0402:R_6k8_0402")
		(at 220.98 62.23 270)
		(mirror x)
		(unit 1)
		(exclude_from_sim no)
		(in_bom yes)
		(on_board yes)
		(dnp no)
		(fields_autoplaced yes)
		(property "Reference" "R912"
			(at 218.44 58.42 90)
			(effects
				(font
					(size 1.27 1.27)
					(thickness 0.15)
				)
				(justify right)
			)
		)
		(property "Value" "R_6k8_0402"
			(at 208.28 41.91 0)
			(effects
				(font
					(size 1.27 1.27)
					(thickness 0.15)
				)
				(justify left bottom)
				(hide yes)
			)
		)
		(property "Footprint" "antmicro-footprints:R_0402_1005Metric"
			(at 205.74 41.91 0)
			(effects
				(font
					(size 1.27 1.27)
					(thickness 0.15)
				)
				(justify left bottom)
				(hide yes)
			)
		)
		(property "Datasheet" "https://www.bourns.com/docs/product-datasheets/cr.pdf"
			(at 203.2 41.91 0)
			(effects
				(font
					(size 1.27 1.27)
					(thickness 0.15)
				)
				(justify left bottom)
				(hide yes)
			)
		)
		(property "Description" ""
			(at 220.98 62.23 0)
			(effects
				(font
					(size 1.27 1.27)
				)
				(hide yes)
			)
		)
		(property "MPN" "CR0402-FX-6801GLF"
			(at 200.66 41.91 0)
			(effects
				(font
					(size 1.27 1.27)
					(thickness 0.15)
				)
				(justify left bottom)
				(hide yes)
			)
		)
		(property "Manufacturer" "Bourns"
			(at 198.12 41.91 0)
			(effects
				(font
					(size 1.27 1.27)
					(thickness 0.15)
				)
				(justify left bottom)
				(hide yes)
			)
		)
		(property "License" "Apache-2.0"
			(at 195.58 41.91 0)
			(effects
				(font
					(size 1.27 1.27)
					(thickness 0.15)
				)
				(justify left bottom)
				(hide yes)
			)
		)
		(property "Author" "Antmicro"
			(at 193.04 41.91 0)
			(effects
				(font
					(size 1.27 1.27)
					(thickness 0.15)
				)
				(justify left bottom)
				(hide yes)
			)
		)
		(property "Val" "6k8"
			(at 218.44 60.96 90)
			(effects
				(font
					(size 1.27 1.27)
					(thickness 0.15)
				)
				(justify right)
			)
		)
		(property "Tolerance" "1%"
			(at 210.82 41.91 0)
			(effects
				(font
					(size 1.27 1.27)
				)
				(justify left bottom)
				(hide yes)
			)
		)
		(pin "2"
		)
		(pin "1"
		)
		(instances
			(project "cm4-baseboard"
				(path ""
					(reference "R912")
					(unit 1)
				)
			)
			(project "usb"
				(path ""
					(reference "R912")
					(unit 1)
				)
			)
		)
	)
	(symbol
		(lib_id "antmicroTestPoints:TP_0.75mm_SMD")
		(at 370.84 151.13 0)
		(mirror x)
		(unit 1)
		(exclude_from_sim no)
		(in_bom no)
		(on_board yes)
		(dnp no)
		(property "Reference" "TP907"
			(at 375.285 151.13 0)
			(effects
				(font
					(size 1.27 1.27)
				)
				(justify left)
			)
		)
		(property "Value" "TP_0.75mm_SMD"
			(at 370.84 148.59 0)
			(effects
				(font
					(size 1.27 1.27)
					(thickness 0.15)
				)
				(justify left bottom)
				(hide yes)
			)
		)
		(property "Footprint" "antmicro-footprints:TP_SMD_0.75mm"
			(at 375.92 156.21 0)
			(effects
				(font
					(size 1.27 1.27)
					(thickness 0.15)
				)
				(justify left bottom)
				(hide yes)
			)
		)
		(property "Datasheet" ""
			(at 375.92 158.75 0)
			(effects
				(font
					(size 1.27 1.27)
					(thickness 0.15)
				)
				(justify left bottom)
				(hide yes)
			)
		)
		(property "Description" ""
			(at 370.84 151.13 0)
			(effects
				(font
					(size 1.27 1.27)
				)
				(hide yes)
			)
		)
		(property "MPN" ""
			(at 370.84 151.13 0)
			(effects
				(font
					(size 1.27 1.27)
					(thickness 0.15)
				)
				(justify left bottom)
				(hide yes)
			)
		)
		(property "Manufacturer" ""
			(at 370.84 151.13 0)
			(effects
				(font
					(size 1.27 1.27)
					(thickness 0.15)
				)
				(justify left bottom)
				(hide yes)
			)
		)
		(property "Author" "Antmicro"
			(at 386.08 135.89 0)
			(effects
				(font
					(size 1.27 1.27)
					(thickness 0.15)
				)
				(justify left bottom)
				(hide yes)
			)
		)
		(property "License" "Apache-2.0"
			(at 386.08 133.35 0)
			(effects
				(font
					(size 1.27 1.27)
					(thickness 0.15)
				)
				(justify left bottom)
				(hide yes)
			)
		)
		(pin "1"
		)
		(instances
			(project "cm4-baseboard"
				(path ""
					(reference "TP907")
					(unit 1)
				)
			)
			(project "usb"
				(path ""
					(reference "TP907")
					(unit 1)
				)
			)
		)
	)
	(symbol
		(lib_id "antmicroLEDIndicationDiscrete:LED_G_0603_KP-1608CGCK")
		(at 243.84 69.85 270)
		(mirror x)
		(unit 1)
		(exclude_from_sim no)
		(in_bom yes)
		(on_board yes)
		(dnp no)
		(property "Reference" "D907"
			(at 250.19 66.04 90)
			(effects
				(font
					(size 1.27 1.27)
					(thickness 0.15)
				)
			)
		)
		(property "Value" "LED_G_0603_KP-1608CGCK"
			(at 236.22 46.99 0)
			(effects
				(font
					(size 1.27 1.27)
					(thickness 0.15)
				)
				(justify left bottom)
				(hide yes)
			)
		)
		(property "Footprint" "antmicro-footprints:LED_0603_1608Metric_G"
			(at 233.68 46.99 0)
			(effects
				(font
					(size 1.27 1.27)
					(thickness 0.15)
				)
				(justify left bottom)
				(hide yes)
			)
		)
		(property "Datasheet" "http://www.kingbright.com/attachments/file/psearch//000/00/00/KP-1608CGCK(Ver.23B).pdf"
			(at 231.14 46.99 0)
			(effects
				(font
					(size 1.27 1.27)
					(thickness 0.15)
				)
				(justify left bottom)
				(hide yes)
			)
		)
		(property "Description" ""
			(at 243.84 69.85 0)
			(effects
				(font
					(size 1.27 1.27)
				)
				(hide yes)
			)
		)
		(property "MPN" "KP-1608CGCK"
			(at 228.6 46.99 0)
			(effects
				(font
					(size 1.27 1.27)
					(thickness 0.15)
				)
				(justify left bottom)
				(hide yes)
			)
		)
		(property "Manufacturer" "Kingbright"
			(at 226.06 46.99 0)
			(effects
				(font
					(size 1.27 1.27)
					(thickness 0.15)
				)
				(justify left bottom)
				(hide yes)
			)
		)
		(property "Color" "Green"
			(at 250.19 68.58 90)
			(effects
				(font
					(size 1.27 1.27)
				)
			)
		)
		(property "Author" "Antmicro"
			(at 223.52 46.99 0)
			(effects
				(font
					(size 1.27 1.27)
					(thickness 0.15)
				)
				(justify left bottom)
				(hide yes)
			)
		)
		(property "License" "Apache-2.0"
			(at 220.98 46.99 0)
			(effects
				(font
					(size 1.27 1.27)
					(thickness 0.15)
				)
				(justify left bottom)
				(hide yes)
			)
		)
		(pin "2"
		)
		(pin "1"
		)
		(instances
			(project "cm4-baseboard"
				(path ""
					(reference "D907")
					(unit 1)
				)
			)
		)
	)
	(symbol
		(lib_id "antmicroCapacitors0402:C_100n_0402")
		(at 262.89 149.86 270)
		(unit 1)
		(exclude_from_sim no)
		(in_bom yes)
		(on_board yes)
		(dnp no)
		(property "Reference" "C912"
			(at 263.525 150.495 90)
			(effects
				(font
					(size 1.27 1.27)
				)
				(justify left)
			)
		)
		(property "Value" "C_100n_0402"
			(at 259.08 149.86 0)
			(effects
				(font
					(size 1.27 1.27)
					(thickness 0.15)
				)
				(justify left bottom)
				(hide yes)
			)
		)
		(property "Footprint" "antmicro-footprints:C_0402_1005Metric"
			(at 267.97 154.94 0)
			(effects
				(font
					(size 1.27 1.27)
					(thickness 0.15)
				)
				(justify left bottom)
				(hide yes)
			)
		)
		(property "Datasheet" "https://www.murata.com/products/productdetail?partno=GRM155R61H104KE14%23"
			(at 262.89 149.86 0)
			(effects
				(font
					(size 1.27 1.27)
					(thickness 0.15)
				)
				(justify left bottom)
				(hide yes)
			)
		)
		(property "Description" ""
			(at 262.89 149.86 0)
			(effects
				(font
					(size 1.27 1.27)
				)
				(hide yes)
			)
		)
		(property "Manufacturer" "Murata"
			(at 273.05 154.94 0)
			(effects
				(font
					(size 1.27 1.27)
					(thickness 0.15)
				)
				(justify left bottom)
				(hide yes)
			)
		)
		(property "MPN" "GRM155R61H104KE14D"
			(at 270.51 154.94 0)
			(effects
				(font
					(size 1.27 1.27)
					(thickness 0.15)
				)
				(justify left bottom)
				(hide yes)
			)
		)
		(property "Val" "100n"
			(at 263.525 154.305 90)
			(effects
				(font
					(size 1.27 1.27)
					(thickness 0.15)
				)
				(justify left)
			)
		)
		(property "License" "Apache-2.0"
			(at 240.03 170.18 0)
			(effects
				(font
					(size 1.27 1.27)
					(thickness 0.15)
				)
				(justify left bottom)
				(hide yes)
			)
		)
		(property "Author" "Antmicro"
			(at 237.49 170.18 0)
			(effects
				(font
					(size 1.27 1.27)
					(thickness 0.15)
				)
				(justify left bottom)
				(hide yes)
			)
		)
		(property "Voltage" "50V"
			(at 234.95 170.18 0)
			(effects
				(font
					(size 1.27 1.27)
				)
				(justify left bottom)
				(hide yes)
			)
		)
		(property "Dielectric" "X5R"
			(at 232.41 170.18 0)
			(effects
				(font
					(size 1.27 1.27)
				)
				(justify left bottom)
				(hide yes)
			)
		)
		(pin "1"
		)
		(pin "2"
		)
		(instances
			(project "cm4-baseboard"
				(path ""
					(reference "C912")
					(unit 1)
				)
			)
			(project "usb"
				(path ""
					(reference "C912")
					(unit 1)
				)
			)
		)
	)
	(symbol
		(lib_id "antmicroCapacitors0402:C_100n_0402")
		(at 157.48 185.42 270)
		(unit 1)
		(exclude_from_sim no)
		(in_bom yes)
		(on_board yes)
		(dnp no)
		(fields_autoplaced yes)
		(property "Reference" "C904"
			(at 160.02 186.6962 90)
			(effects
				(font
					(size 1.27 1.27)
				)
				(justify left)
			)
		)
		(property "Value" "C_100n_0402"
			(at 147.32 205.74 0)
			(effects
				(font
					(size 1.27 1.27)
					(thickness 0.15)
				)
				(justify left bottom)
				(hide yes)
			)
		)
		(property "Footprint" "antmicro-footprints:C_0402_1005Metric"
			(at 144.78 205.74 0)
			(effects
				(font
					(size 1.27 1.27)
					(thickness 0.15)
				)
				(justify left bottom)
				(hide yes)
			)
		)
		(property "Datasheet" "https://www.murata.com/products/productdetail?partno=GRM155R61H104KE14%23"
			(at 142.24 205.74 0)
			(effects
				(font
					(size 1.27 1.27)
					(thickness 0.15)
				)
				(justify left bottom)
				(hide yes)
			)
		)
		(property "Description" ""
			(at 157.48 185.42 0)
			(effects
				(font
					(size 1.27 1.27)
				)
				(hide yes)
			)
		)
		(property "Manufacturer" "Murata"
			(at 137.16 205.74 0)
			(effects
				(font
					(size 1.27 1.27)
					(thickness 0.15)
				)
				(justify left bottom)
				(hide yes)
			)
		)
		(property "MPN" "GRM155R61H104KE14D"
			(at 139.7 205.74 0)
			(effects
				(font
					(size 1.27 1.27)
					(thickness 0.15)
				)
				(justify left bottom)
				(hide yes)
			)
		)
		(property "Val" "100n"
			(at 160.02 189.2362 90)
			(effects
				(font
					(size 1.27 1.27)
					(thickness 0.15)
				)
				(justify left)
			)
		)
		(property "License" "Apache-2.0"
			(at 134.62 205.74 0)
			(effects
				(font
					(size 1.27 1.27)
					(thickness 0.15)
				)
				(justify left bottom)
				(hide yes)
			)
		)
		(property "Author" "Antmicro"
			(at 132.08 205.74 0)
			(effects
				(font
					(size 1.27 1.27)
					(thickness 0.15)
				)
				(justify left bottom)
				(hide yes)
			)
		)
		(property "Voltage" "50V"
			(at 129.54 205.74 0)
			(effects
				(font
					(size 1.27 1.27)
				)
				(justify left bottom)
				(hide yes)
			)
		)
		(property "Dielectric" "X5R"
			(at 127 205.74 0)
			(effects
				(font
					(size 1.27 1.27)
				)
				(justify left bottom)
				(hide yes)
			)
		)
		(pin "1"
		)
		(pin "2"
		)
		(instances
			(project "cm4-baseboard"
				(path ""
					(reference "C904")
					(unit 1)
				)
			)
			(project "usb"
				(path ""
					(reference "C904")
					(unit 1)
				)
			)
		)
	)
	(symbol
		(lib_id "antmicroTransistorsFETsMOSFETsSingle:PJE138K")
		(at 173.99 210.82 0)
		(mirror y)
		(unit 1)
		(exclude_from_sim no)
		(in_bom yes)
		(on_board yes)
		(dnp no)
		(fields_autoplaced yes)
		(property "Reference" "Q901"
			(at 162.56 207.0099 0)
			(effects
				(font
					(size 1.27 1.27)
					(thickness 0.15)
				)
				(justify left)
			)
		)
		(property "Value" "PJE138K"
			(at 162.56 209.5499 0)
			(effects
				(font
					(size 1.27 1.27)
					(thickness 0.15)
				)
				(justify left)
			)
		)
		(property "Footprint" "antmicro-footprints:SOT-523"
			(at 151.13 222.25 0)
			(effects
				(font
					(size 1.27 1.27)
					(thickness 0.15)
				)
				(justify left bottom)
				(hide yes)
			)
		)
		(property "Datasheet" "https://www.mouser.com/datasheet/2/1057/PJE138K-1876698.pdf"
			(at 151.13 224.79 0)
			(effects
				(font
					(size 1.27 1.27)
					(thickness 0.15)
				)
				(justify left bottom)
				(hide yes)
			)
		)
		(property "Description" ""
			(at 173.99 210.82 0)
			(effects
				(font
					(size 1.27 1.27)
				)
				(hide yes)
			)
		)
		(property "MPN" "PJE138K_R1_00001"
			(at 151.13 227.33 0)
			(effects
				(font
					(size 1.27 1.27)
					(thickness 0.15)
				)
				(justify left bottom)
				(hide yes)
			)
		)
		(property "Manufacturer" "PANJIT"
			(at 151.13 229.87 0)
			(effects
				(font
					(size 1.27 1.27)
					(thickness 0.15)
				)
				(justify left bottom)
				(hide yes)
			)
		)
		(property "Author" "Antmicro"
			(at 151.13 232.41 0)
			(effects
				(font
					(size 1.27 1.27)
					(thickness 0.15)
				)
				(justify left bottom)
				(hide yes)
			)
		)
		(property "License" "Apache-2.0"
			(at 151.13 234.95 0)
			(effects
				(font
					(size 1.27 1.27)
					(thickness 0.15)
				)
				(justify left bottom)
				(hide yes)
			)
		)
		(pin "1"
		)
		(pin "2"
		)
		(pin "3"
		)
		(instances
			(project "cm4-baseboard"
				(path ""
					(reference "Q901")
					(unit 1)
				)
			)
			(project "usb"
				(path ""
					(reference "Q901")
					(unit 1)
				)
			)
		)
	)
	(symbol
		(lib_id "antmicropower:GND")
		(at 335.28 156.21 0)
		(unit 1)
		(exclude_from_sim no)
		(in_bom yes)
		(on_board yes)
		(dnp no)
		(property "Reference" "#PWR0953"
			(at 344.17 158.75 0)
			(effects
				(font
					(size 1.27 1.27)
					(thickness 0.15)
				)
				(justify left bottom)
				(hide yes)
			)
		)
		(property "Value" "GND"
			(at 335.28 161.29 0)
			(effects
				(font
					(size 1.27 1.27)
					(thickness 0.15)
				)
			)
		)
		(property "Footprint" ""
			(at 344.17 163.83 0)
			(effects
				(font
					(size 1.27 1.27)
					(thickness 0.15)
				)
				(justify left bottom)
				(hide yes)
			)
		)
		(property "Datasheet" ""
			(at 344.17 168.91 0)
			(effects
				(font
					(size 1.27 1.27)
					(thickness 0.15)
				)
				(justify left bottom)
				(hide yes)
			)
		)
		(property "Description" ""
			(at 335.28 156.21 0)
			(effects
				(font
					(size 1.27 1.27)
				)
				(hide yes)
			)
		)
		(property "Author" "Antmicro"
			(at 344.17 163.83 0)
			(effects
				(font
					(size 1.27 1.27)
					(thickness 0.15)
				)
				(justify left bottom)
				(hide yes)
			)
		)
		(property "License" "Apache-2.0"
			(at 344.17 166.37 0)
			(effects
				(font
					(size 1.27 1.27)
					(thickness 0.15)
				)
				(justify left bottom)
				(hide yes)
			)
		)
		(pin "1"
		)
		(instances
			(project "cm4-baseboard"
				(path ""
					(reference "#PWR0953")
					(unit 1)
				)
			)
			(project "usb"
				(path ""
					(reference "#PWR0953")
					(unit 1)
				)
			)
		)
	)
	(symbol
		(lib_id "antmicropower:GND")
		(at 293.37 156.21 0)
		(unit 1)
		(exclude_from_sim no)
		(in_bom yes)
		(on_board yes)
		(dnp no)
		(fields_autoplaced yes)
		(property "Reference" "#PWR0946"
			(at 293.37 162.56 0)
			(effects
				(font
					(size 1.27 1.27)
				)
				(hide yes)
			)
		)
		(property "Value" "GND"
			(at 293.37 161.29 0)
			(effects
				(font
					(size 1.27 1.27)
				)
			)
		)
		(property "Footprint" ""
			(at 302.26 163.83 0)
			(effects
				(font
					(size 1.27 1.27)
					(thickness 0.15)
				)
				(justify left bottom)
				(hide yes)
			)
		)
		(property "Datasheet" ""
			(at 302.26 168.91 0)
			(effects
				(font
					(size 1.27 1.27)
					(thickness 0.15)
				)
				(justify left bottom)
				(hide yes)
			)
		)
		(property "Description" ""
			(at 293.37 156.21 0)
			(effects
				(font
					(size 1.27 1.27)
				)
				(hide yes)
			)
		)
		(property "Author" "Antmicro"
			(at 302.26 163.83 0)
			(effects
				(font
					(size 1.27 1.27)
					(thickness 0.15)
				)
				(justify left bottom)
				(hide yes)
			)
		)
		(property "License" "Apache-2.0"
			(at 302.26 166.37 0)
			(effects
				(font
					(size 1.27 1.27)
					(thickness 0.15)
				)
				(justify left bottom)
				(hide yes)
			)
		)
		(pin "1"
		)
		(instances
			(project "cm4-baseboard"
				(path ""
					(reference "#PWR0946")
					(unit 1)
				)
			)
			(project "usb"
				(path ""
					(reference "#PWR0946")
					(unit 1)
				)
			)
		)
	)
	(symbol
		(lib_id "antmicroDiodesRectifiersSingle:RB521S30T1G")
		(at 273.05 69.85 0)
		(mirror y)
		(unit 1)
		(exclude_from_sim no)
		(in_bom yes)
		(on_board yes)
		(dnp no)
		(property "Reference" "D910"
			(at 270.51 65.405 0)
			(effects
				(font
					(size 1.27 1.27)
				)
			)
		)
		(property "Value" "RB521S30T1G"
			(at 274.32 67.31 0)
			(effects
				(font
					(size 1.27 1.27)
					(thickness 0.15)
				)
				(justify left bottom)
				(hide yes)
			)
		)
		(property "Footprint" "antmicro-footprints:SOD-523"
			(at 250.19 80.01 0)
			(effects
				(font
					(size 1.27 1.27)
					(thickness 0.15)
				)
				(justify left bottom)
				(hide yes)
			)
		)
		(property "Datasheet" "https://www.onsemi.com/pdf/datasheet/rb521s30t1-d.pdf"
			(at 250.19 82.55 0)
			(effects
				(font
					(size 1.27 1.27)
					(thickness 0.15)
				)
				(justify left bottom)
				(hide yes)
			)
		)
		(property "Description" ""
			(at 273.05 69.85 0)
			(effects
				(font
					(size 1.27 1.27)
				)
				(hide yes)
			)
		)
		(property "MPN" "RB521S30T1G"
			(at 270.51 67.945 0)
			(effects
				(font
					(size 1.27 1.27)
					(thickness 0.15)
				)
			)
		)
		(property "Manufacturer" "ON Semiconductor"
			(at 250.19 87.63 0)
			(effects
				(font
					(size 1.27 1.27)
					(thickness 0.15)
				)
				(justify left bottom)
				(hide yes)
			)
		)
		(property "Author" "Antmicro"
			(at 250.19 90.17 0)
			(effects
				(font
					(size 1.27 1.27)
					(thickness 0.15)
				)
				(justify left bottom)
				(hide yes)
			)
		)
		(property "License" "Apache-2.0"
			(at 250.19 92.71 0)
			(effects
				(font
					(size 1.27 1.27)
					(thickness 0.15)
				)
				(justify left bottom)
				(hide yes)
			)
		)
		(pin "1"
		)
		(pin "2"
		)
		(instances
			(project "cm4-baseboard"
				(path ""
					(reference "D910")
					(unit 1)
				)
			)
			(project "usb"
				(path ""
					(reference "D910")
					(unit 1)
				)
			)
		)
	)
	(symbol
		(lib_id "antmicropower:GND")
		(at 102.87 86.36 0)
		(unit 1)
		(exclude_from_sim no)
		(in_bom yes)
		(on_board yes)
		(dnp no)
		(property "Reference" "#PWR0910"
			(at 111.76 88.9 0)
			(effects
				(font
					(size 1.27 1.27)
					(thickness 0.15)
				)
				(justify left bottom)
				(hide yes)
			)
		)
		(property "Value" "GND"
			(at 100.965 90.805 0)
			(effects
				(font
					(size 1.27 1.27)
					(thickness 0.15)
				)
				(justify left bottom)
			)
		)
		(property "Footprint" ""
			(at 111.76 93.98 0)
			(effects
				(font
					(size 1.27 1.27)
					(thickness 0.15)
				)
				(justify left bottom)
				(hide yes)
			)
		)
		(property "Datasheet" ""
			(at 111.76 99.06 0)
			(effects
				(font
					(size 1.27 1.27)
					(thickness 0.15)
				)
				(justify left bottom)
				(hide yes)
			)
		)
		(property "Description" ""
			(at 102.87 86.36 0)
			(effects
				(font
					(size 1.27 1.27)
				)
				(hide yes)
			)
		)
		(property "Author" "Antmicro"
			(at 111.76 93.98 0)
			(effects
				(font
					(size 1.27 1.27)
					(thickness 0.15)
				)
				(justify left bottom)
				(hide yes)
			)
		)
		(property "License" "Apache-2.0"
			(at 111.76 96.52 0)
			(effects
				(font
					(size 1.27 1.27)
					(thickness 0.15)
				)
				(justify left bottom)
				(hide yes)
			)
		)
		(pin "1"
		)
		(instances
			(project "cm4-baseboard"
				(path ""
					(reference "#PWR0910")
					(unit 1)
				)
			)
			(project "usb"
				(path ""
					(reference "#PWR0910")
					(unit 1)
				)
			)
		)
	)
	(symbol
		(lib_id "antmicroResistors0402:R_10k_0402")
		(at 92.71 73.66 270)
		(unit 1)
		(exclude_from_sim no)
		(in_bom yes)
		(on_board yes)
		(dnp no)
		(property "Reference" "R933"
			(at 86.36 77.47 90)
			(effects
				(font
					(size 1.27 1.27)
				)
				(justify left)
			)
		)
		(property "Value" "R_10k_0402"
			(at 80.01 93.98 0)
			(effects
				(font
					(size 1.27 1.27)
					(thickness 0.15)
				)
				(justify left bottom)
				(hide yes)
			)
		)
		(property "Footprint" "antmicro-footprints:R_0402_1005Metric"
			(at 77.47 93.98 0)
			(effects
				(font
					(size 1.27 1.27)
					(thickness 0.15)
				)
				(justify left bottom)
				(hide yes)
			)
		)
		(property "Datasheet" "https://www.bourns.com/docs/product-datasheets/cr.pdf"
			(at 74.93 93.98 0)
			(effects
				(font
					(size 1.27 1.27)
					(thickness 0.15)
				)
				(justify left bottom)
				(hide yes)
			)
		)
		(property "Description" ""
			(at 92.71 73.66 0)
			(effects
				(font
					(size 1.27 1.27)
				)
				(hide yes)
			)
		)
		(property "Manufacturer" "Bourns"
			(at 69.85 93.98 0)
			(effects
				(font
					(size 1.27 1.27)
					(thickness 0.15)
				)
				(justify left bottom)
				(hide yes)
			)
		)
		(property "MPN" "CR0402-FX-1002GLF"
			(at 72.39 93.98 0)
			(effects
				(font
					(size 1.27 1.27)
					(thickness 0.15)
				)
				(justify left bottom)
				(hide yes)
			)
		)
		(property "Val" "10k"
			(at 87.63 74.93 90)
			(effects
				(font
					(size 1.27 1.27)
					(thickness 0.15)
				)
				(justify left)
			)
		)
		(property "License" "Apache-2.0"
			(at 67.31 93.98 0)
			(effects
				(font
					(size 1.27 1.27)
					(thickness 0.15)
				)
				(justify left bottom)
				(hide yes)
			)
		)
		(property "Author" "Antmicro"
			(at 64.77 93.98 0)
			(effects
				(font
					(size 1.27 1.27)
					(thickness 0.15)
				)
				(justify left bottom)
				(hide yes)
			)
		)
		(property "Tolerance" "1%"
			(at 82.55 93.98 0)
			(effects
				(font
					(size 1.27 1.27)
				)
				(justify left bottom)
				(hide yes)
			)
		)
		(pin "1"
		)
		(pin "2"
		)
		(instances
			(project "cm4-baseboard"
				(path ""
					(reference "R933")
					(unit 1)
				)
			)
		)
	)
	(symbol
		(lib_id "antmicroResistors0402:R_470R_0402")
		(at 322.58 110.49 90)
		(unit 1)
		(exclude_from_sim no)
		(in_bom yes)
		(on_board yes)
		(dnp no)
		(property "Reference" "R921"
			(at 323.85 106.68 90)
			(effects
				(font
					(size 1.27 1.27)
					(thickness 0.15)
				)
				(justify right)
			)
		)
		(property "Value" "R_470R_0402"
			(at 335.28 90.17 0)
			(effects
				(font
					(size 1.27 1.27)
					(thickness 0.15)
				)
				(justify left bottom)
				(hide yes)
			)
		)
		(property "Footprint" "antmicro-footprints:R_0402_1005Metric"
			(at 337.82 90.17 0)
			(effects
				(font
					(size 1.27 1.27)
					(thickness 0.15)
				)
				(justify left bottom)
				(hide yes)
			)
		)
		(property "Datasheet" "https://www.bourns.com/docs/product-datasheets/cr.pdf"
			(at 340.36 90.17 0)
			(effects
				(font
					(size 1.27 1.27)
					(thickness 0.15)
				)
				(justify left bottom)
				(hide yes)
			)
		)
		(property "Description" ""
			(at 322.58 110.49 0)
			(effects
				(font
					(size 1.27 1.27)
				)
				(hide yes)
			)
		)
		(property "MPN" "CR0402-FX-4700GLF"
			(at 342.9 90.17 0)
			(effects
				(font
					(size 1.27 1.27)
					(thickness 0.15)
				)
				(justify left bottom)
				(hide yes)
			)
		)
		(property "Manufacturer" "Bourns"
			(at 345.44 90.17 0)
			(effects
				(font
					(size 1.27 1.27)
					(thickness 0.15)
				)
				(justify left bottom)
				(hide yes)
			)
		)
		(property "License" "Apache-2.0"
			(at 347.98 90.17 0)
			(effects
				(font
					(size 1.27 1.27)
					(thickness 0.15)
				)
				(justify left bottom)
				(hide yes)
			)
		)
		(property "Author" "Antmicro"
			(at 350.52 90.17 0)
			(effects
				(font
					(size 1.27 1.27)
					(thickness 0.15)
				)
				(justify left bottom)
				(hide yes)
			)
		)
		(property "Val" "470R"
			(at 323.85 109.22 90)
			(effects
				(font
					(size 1.27 1.27)
					(thickness 0.15)
				)
				(justify right)
			)
		)
		(property "Tolerance" "1%"
			(at 332.74 90.17 0)
			(effects
				(font
					(size 1.27 1.27)
				)
				(justify left bottom)
				(hide yes)
			)
		)
		(pin "1"
		)
		(pin "2"
		)
		(instances
			(project "cm4-baseboard"
				(path ""
					(reference "R921")
					(unit 1)
				)
			)
			(project "usb"
				(path ""
					(reference "R921")
					(unit 1)
				)
			)
		)
	)
	(symbol
		(lib_id "antmicroCapacitors0402:C_100n_0402")
		(at 147.32 137.16 270)
		(unit 1)
		(exclude_from_sim no)
		(in_bom yes)
		(on_board yes)
		(dnp no)
		(fields_autoplaced yes)
		(property "Reference" "C903"
			(at 150.495 138.4363 90)
			(effects
				(font
					(size 1.27 1.27)
				)
				(justify left)
			)
		)
		(property "Value" "C_100n_0402"
			(at 143.51 137.16 0)
			(effects
				(font
					(size 1.27 1.27)
					(thickness 0.15)
				)
				(justify left bottom)
				(hide yes)
			)
		)
		(property "Footprint" "antmicro-footprints:C_0402_1005Metric"
			(at 152.4 142.24 0)
			(effects
				(font
					(size 1.27 1.27)
					(thickness 0.15)
				)
				(justify left bottom)
				(hide yes)
			)
		)
		(property "Datasheet" "https://www.murata.com/products/productdetail?partno=GRM155R61H104KE14%23"
			(at 147.32 137.16 0)
			(effects
				(font
					(size 1.27 1.27)
					(thickness 0.15)
				)
				(justify left bottom)
				(hide yes)
			)
		)
		(property "Description" ""
			(at 147.32 137.16 0)
			(effects
				(font
					(size 1.27 1.27)
				)
				(hide yes)
			)
		)
		(property "Manufacturer" "Murata"
			(at 157.48 142.24 0)
			(effects
				(font
					(size 1.27 1.27)
					(thickness 0.15)
				)
				(justify left bottom)
				(hide yes)
			)
		)
		(property "MPN" "GRM155R61H104KE14D"
			(at 154.94 142.24 0)
			(effects
				(font
					(size 1.27 1.27)
					(thickness 0.15)
				)
				(justify left bottom)
				(hide yes)
			)
		)
		(property "Val" "100n"
			(at 150.495 141.6112 90)
			(effects
				(font
					(size 1.27 1.27)
					(thickness 0.15)
				)
				(justify left)
			)
		)
		(property "License" "Apache-2.0"
			(at 124.46 157.48 0)
			(effects
				(font
					(size 1.27 1.27)
					(thickness 0.15)
				)
				(justify left bottom)
				(hide yes)
			)
		)
		(property "Author" "Antmicro"
			(at 121.92 157.48 0)
			(effects
				(font
					(size 1.27 1.27)
					(thickness 0.15)
				)
				(justify left bottom)
				(hide yes)
			)
		)
		(property "Voltage" "50V"
			(at 119.38 157.48 0)
			(effects
				(font
					(size 1.27 1.27)
				)
				(justify left bottom)
				(hide yes)
			)
		)
		(property "Dielectric" "X5R"
			(at 116.84 157.48 0)
			(effects
				(font
					(size 1.27 1.27)
				)
				(justify left bottom)
				(hide yes)
			)
		)
		(pin "1"
		)
		(pin "2"
		)
		(instances
			(project "cm4-baseboard"
				(path ""
					(reference "C903")
					(unit 1)
				)
			)
			(project "usb"
				(path ""
					(reference "C903")
					(unit 1)
				)
			)
		)
	)
	(symbol
		(lib_id "antmicroCapacitors0402:C_1u_25V_0402")
		(at 231.14 191.77 270)
		(mirror x)
		(unit 1)
		(exclude_from_sim no)
		(in_bom yes)
		(on_board yes)
		(dnp no)
		(property "Reference" "C931"
			(at 236.22 186.69 90)
			(effects
				(font
					(size 1.27 1.27)
					(thickness 0.15)
				)
				(justify right)
			)
		)
		(property "Value" "C_1u_25V_0402"
			(at 220.98 171.45 0)
			(effects
				(font
					(size 1.27 1.27)
					(thickness 0.15)
				)
				(justify left bottom)
				(hide yes)
			)
		)
		(property "Footprint" "antmicro-footprints:C_0402_1005Metric"
			(at 218.44 171.45 0)
			(effects
				(font
					(size 1.27 1.27)
					(thickness 0.15)
				)
				(justify left bottom)
				(hide yes)
			)
		)
		(property "Datasheet" "https://www.murata.com/products/productdetail?partno=GRM155R61E105KE11%23"
			(at 215.9 171.45 0)
			(effects
				(font
					(size 1.27 1.27)
					(thickness 0.15)
				)
				(justify left bottom)
				(hide yes)
			)
		)
		(property "Description" ""
			(at 231.14 191.77 0)
			(effects
				(font
					(size 1.27 1.27)
				)
				(hide yes)
			)
		)
		(property "MPN" "GRM155R61E105KE11J"
			(at 213.36 171.45 0)
			(effects
				(font
					(size 1.27 1.27)
					(thickness 0.15)
				)
				(justify left bottom)
				(hide yes)
			)
		)
		(property "Manufacturer" "Murata"
			(at 210.82 171.45 0)
			(effects
				(font
					(size 1.27 1.27)
					(thickness 0.15)
				)
				(justify left bottom)
				(hide yes)
			)
		)
		(property "License" "Apache-2.0"
			(at 208.28 171.45 0)
			(effects
				(font
					(size 1.27 1.27)
					(thickness 0.15)
				)
				(justify left bottom)
				(hide yes)
			)
		)
		(property "Author" "Antmicro"
			(at 205.74 171.45 0)
			(effects
				(font
					(size 1.27 1.27)
					(thickness 0.15)
				)
				(justify left bottom)
				(hide yes)
			)
		)
		(property "Val" "1u"
			(at 236.22 189.23 90)
			(effects
				(font
					(size 1.27 1.27)
					(thickness 0.15)
				)
				(justify right)
			)
		)
		(property "Voltage" "25V"
			(at 236.22 191.77 90)
			(effects
				(font
					(size 1.27 1.27)
				)
				(justify right)
				(hide yes)
			)
		)
		(property "Dielectric" "X5R"
			(at 200.66 171.45 0)
			(effects
				(font
					(size 1.27 1.27)
				)
				(justify left bottom)
				(hide yes)
			)
		)
		(pin "1"
		)
		(pin "2"
		)
		(instances
			(project "cm4-baseboard"
				(path ""
					(reference "C931")
					(unit 1)
				)
			)
			(project "usb"
				(path ""
					(reference "C931")
					(unit 1)
				)
			)
		)
	)
	(symbol
		(lib_id "antmicroCapacitors0402:C_100n_0402")
		(at 208.28 191.77 270)
		(mirror x)
		(unit 1)
		(exclude_from_sim no)
		(in_bom yes)
		(on_board yes)
		(dnp no)
		(fields_autoplaced yes)
		(property "Reference" "C930"
			(at 210.82 187.9536 90)
			(effects
				(font
					(size 1.27 1.27)
				)
				(justify left)
			)
		)
		(property "Value" "C_100n_0402"
			(at 204.47 191.77 0)
			(effects
				(font
					(size 1.27 1.27)
				)
				(justify left bottom)
				(hide yes)
			)
		)
		(property "Footprint" "antmicro-footprints:C_0402_1005Metric"
			(at 213.36 186.69 0)
			(effects
				(font
					(size 1.524 1.524)
				)
				(justify left bottom)
				(hide yes)
			)
		)
		(property "Datasheet" "https://www.murata.com/products/productdetail?partno=GRM155R61H104KE14%23"
			(at 208.28 191.77 0)
			(effects
				(font
					(size 1.27 1.27)
				)
				(justify left bottom)
				(hide yes)
			)
		)
		(property "Description" ""
			(at 208.28 191.77 0)
			(effects
				(font
					(size 1.27 1.27)
				)
				(hide yes)
			)
		)
		(property "Manufacturer" "Murata"
			(at 218.44 186.69 0)
			(effects
				(font
					(size 1.524 1.524)
				)
				(justify left bottom)
				(hide yes)
			)
		)
		(property "MPN" "GRM155R61H104KE14D"
			(at 215.9 186.69 0)
			(effects
				(font
					(size 1.524 1.524)
				)
				(justify left bottom)
				(hide yes)
			)
		)
		(property "Val" "100n"
			(at 210.82 190.4936 90)
			(effects
				(font
					(size 1.27 1.27)
				)
				(justify left)
			)
		)
		(property "License" "Apache-2.0"
			(at 185.42 171.45 0)
			(effects
				(font
					(size 1.27 1.27)
					(thickness 0.15)
				)
				(justify left bottom)
				(hide yes)
			)
		)
		(property "Author" "Antmicro"
			(at 182.88 171.45 0)
			(effects
				(font
					(size 1.27 1.27)
					(thickness 0.15)
				)
				(justify left bottom)
				(hide yes)
			)
		)
		(property "Voltage" "50V"
			(at 180.34 171.45 0)
			(effects
				(font
					(size 1.27 1.27)
				)
				(justify left bottom)
				(hide yes)
			)
		)
		(property "Dielectric" "X5R"
			(at 177.8 171.45 0)
			(effects
				(font
					(size 1.27 1.27)
				)
				(justify left bottom)
				(hide yes)
			)
		)
		(pin "1"
		)
		(pin "2"
		)
		(instances
			(project "cm4-baseboard"
				(path ""
					(reference "C930")
					(unit 1)
				)
			)
			(project "usb"
				(path ""
					(reference "C930")
					(unit 1)
				)
			)
		)
	)
	(symbol
		(lib_id "antmicroCapacitors0402:C_100n_0402")
		(at 299.72 71.12 270)
		(unit 1)
		(exclude_from_sim no)
		(in_bom yes)
		(on_board yes)
		(dnp no)
		(fields_autoplaced yes)
		(property "Reference" "C910"
			(at 302.26 72.3963 90)
			(effects
				(font
					(size 1.27 1.27)
				)
				(justify left)
			)
		)
		(property "Value" "C_100n_0402"
			(at 295.91 71.12 0)
			(effects
				(font
					(size 1.27 1.27)
					(thickness 0.15)
				)
				(justify left bottom)
				(hide yes)
			)
		)
		(property "Footprint" "antmicro-footprints:C_0402_1005Metric"
			(at 304.8 76.2 0)
			(effects
				(font
					(size 1.27 1.27)
					(thickness 0.15)
				)
				(justify left bottom)
				(hide yes)
			)
		)
		(property "Datasheet" "https://www.murata.com/products/productdetail?partno=GRM155R61H104KE14%23"
			(at 299.72 71.12 0)
			(effects
				(font
					(size 1.27 1.27)
					(thickness 0.15)
				)
				(justify left bottom)
				(hide yes)
			)
		)
		(property "Description" ""
			(at 299.72 71.12 0)
			(effects
				(font
					(size 1.27 1.27)
				)
				(hide yes)
			)
		)
		(property "Manufacturer" "Murata"
			(at 309.88 76.2 0)
			(effects
				(font
					(size 1.27 1.27)
					(thickness 0.15)
				)
				(justify left bottom)
				(hide yes)
			)
		)
		(property "MPN" "GRM155R61H104KE14D"
			(at 307.34 76.2 0)
			(effects
				(font
					(size 1.27 1.27)
					(thickness 0.15)
				)
				(justify left bottom)
				(hide yes)
			)
		)
		(property "Val" "100n"
			(at 302.26 75.5712 90)
			(effects
				(font
					(size 1.27 1.27)
					(thickness 0.15)
				)
				(justify left)
			)
		)
		(property "License" "Apache-2.0"
			(at 276.86 91.44 0)
			(effects
				(font
					(size 1.27 1.27)
					(thickness 0.15)
				)
				(justify left bottom)
				(hide yes)
			)
		)
		(property "Author" "Antmicro"
			(at 274.32 91.44 0)
			(effects
				(font
					(size 1.27 1.27)
					(thickness 0.15)
				)
				(justify left bottom)
				(hide yes)
			)
		)
		(property "Voltage" "50V"
			(at 271.78 91.44 0)
			(effects
				(font
					(size 1.27 1.27)
				)
				(justify left bottom)
				(hide yes)
			)
		)
		(property "Dielectric" "X5R"
			(at 269.24 91.44 0)
			(effects
				(font
					(size 1.27 1.27)
				)
				(justify left bottom)
				(hide yes)
			)
		)
		(pin "1"
		)
		(pin "2"
		)
		(instances
			(project "cm4-baseboard"
				(path ""
					(reference "C910")
					(unit 1)
				)
			)
			(project "usb"
				(path ""
					(reference "C910")
					(unit 1)
				)
			)
		)
	)
	(symbol
		(lib_id "antmicropower:GND")
		(at 281.94 45.72 0)
		(unit 1)
		(exclude_from_sim no)
		(in_bom yes)
		(on_board yes)
		(dnp no)
		(property "Reference" "#PWR0941"
			(at 281.94 52.07 0)
			(effects
				(font
					(size 1.27 1.27)
				)
				(hide yes)
			)
		)
		(property "Value" "GND"
			(at 281.94 49.53 0)
			(effects
				(font
					(size 1.27 1.27)
				)
			)
		)
		(property "Footprint" ""
			(at 290.83 53.34 0)
			(effects
				(font
					(size 1.27 1.27)
					(thickness 0.15)
				)
				(justify left bottom)
				(hide yes)
			)
		)
		(property "Datasheet" ""
			(at 290.83 58.42 0)
			(effects
				(font
					(size 1.27 1.27)
					(thickness 0.15)
				)
				(justify left bottom)
				(hide yes)
			)
		)
		(property "Description" ""
			(at 281.94 45.72 0)
			(effects
				(font
					(size 1.27 1.27)
				)
				(hide yes)
			)
		)
		(property "Author" "Antmicro"
			(at 290.83 53.34 0)
			(effects
				(font
					(size 1.27 1.27)
					(thickness 0.15)
				)
				(justify left bottom)
				(hide yes)
			)
		)
		(property "License" "Apache-2.0"
			(at 290.83 55.88 0)
			(effects
				(font
					(size 1.27 1.27)
					(thickness 0.15)
				)
				(justify left bottom)
				(hide yes)
			)
		)
		(pin "1"
		)
		(instances
			(project "cm4-baseboard"
				(path ""
					(reference "#PWR0941")
					(unit 1)
				)
			)
			(project "usb"
				(path ""
					(reference "#PWR0941")
					(unit 1)
				)
			)
		)
	)
	(symbol
		(lib_id "antmicroCommonModeChokes:Choke_DLW21SN900SQ2L")
		(at 49.53 210.82 0)
		(unit 1)
		(exclude_from_sim no)
		(in_bom yes)
		(on_board yes)
		(dnp no)
		(property "Reference" "T901"
			(at 54.61 204.47 0)
			(effects
				(font
					(size 1.27 1.27)
					(thickness 0.15)
				)
			)
		)
		(property "Value" "Choke_DLW21SN900SQ2L"
			(at 64.77 220.98 0)
			(effects
				(font
					(size 1.27 1.27)
					(thickness 0.15)
				)
				(justify left bottom)
				(hide yes)
			)
		)
		(property "Footprint" "antmicro-footprints:Choke_Murata-DLW21"
			(at 64.77 223.52 0)
			(effects
				(font
					(size 1.27 1.27)
					(thickness 0.15)
				)
				(justify left bottom)
				(hide yes)
			)
		)
		(property "Datasheet" "https://www.murata.com/en-us/products/productdetail?partno=DLW21SN900SQ2%23"
			(at 64.77 226.06 0)
			(effects
				(font
					(size 1.27 1.27)
					(thickness 0.15)
				)
				(justify left bottom)
				(hide yes)
			)
		)
		(property "Description" ""
			(at 49.53 210.82 0)
			(effects
				(font
					(size 1.27 1.27)
				)
				(hide yes)
			)
		)
		(property "Manufacturer" "Murata"
			(at 64.77 228.6 0)
			(effects
				(font
					(size 1.27 1.27)
					(thickness 0.15)
				)
				(justify left bottom)
				(hide yes)
			)
		)
		(property "MPN" "DLW21SN900SQ2L"
			(at 54.61 207.01 0)
			(effects
				(font
					(size 1.27 1.27)
					(thickness 0.15)
				)
			)
		)
		(property "IMax" "0.33 A"
			(at 64.77 231.14 0)
			(effects
				(font
					(size 1.27 1.27)
					(thickness 0.15)
				)
				(justify left bottom)
				(hide yes)
			)
		)
		(property "Author" "Antmicro"
			(at 64.77 233.68 0)
			(effects
				(font
					(size 1.27 1.27)
					(thickness 0.15)
				)
				(justify left bottom)
				(hide yes)
			)
		)
		(property "License" "Apache-2.0"
			(at 64.77 236.22 0)
			(effects
				(font
					(size 1.27 1.27)
					(thickness 0.15)
				)
				(justify left bottom)
				(hide yes)
			)
		)
		(pin "4"
		)
		(pin "1"
		)
		(pin "2"
		)
		(pin "3"
		)
		(instances
			(project "cm4-baseboard"
				(path ""
					(reference "T901")
					(unit 1)
				)
			)
			(project "usb"
				(path ""
					(reference "T901")
					(unit 1)
				)
			)
		)
	)
	(symbol
		(lib_id "antmicroCapacitorsmisc:C_22u_25V_0805")
		(at 160.02 60.96 90)
		(mirror x)
		(unit 1)
		(exclude_from_sim no)
		(in_bom yes)
		(on_board yes)
		(dnp no)
		(fields_autoplaced yes)
		(property "Reference" "C905"
			(at 157.48 60.9662 90)
			(effects
				(font
					(size 1.27 1.27)
				)
				(justify left)
			)
		)
		(property "Value" "C_22u_25V_0805"
			(at 163.83 60.96 0)
			(effects
				(font
					(size 1.27 1.27)
				)
				(justify left bottom)
				(hide yes)
			)
		)
		(property "Footprint" "antmicro-footprints:C_0805_2012Metric"
			(at 154.94 66.04 0)
			(effects
				(font
					(size 1.524 1.524)
				)
				(justify left bottom)
				(hide yes)
			)
		)
		(property "Datasheet" "https://product.samsungsem.com/mlcc/CL21A226MAYNNN.do"
			(at 160.02 60.96 0)
			(effects
				(font
					(size 1.27 1.27)
				)
				(justify left bottom)
				(hide yes)
			)
		)
		(property "Description" ""
			(at 160.02 60.96 0)
			(effects
				(font
					(size 1.27 1.27)
				)
				(hide yes)
			)
		)
		(property "Manufacturer" "Samsung Electro-Mechanics"
			(at 149.86 66.04 0)
			(effects
				(font
					(size 1.524 1.524)
				)
				(justify left bottom)
				(hide yes)
			)
		)
		(property "MPN" "CL21A226MAYNNNE"
			(at 152.4 66.04 0)
			(effects
				(font
					(size 1.524 1.524)
				)
				(justify left bottom)
				(hide yes)
			)
		)
		(property "Val" "22u"
			(at 157.48 63.5062 90)
			(effects
				(font
					(size 1.27 1.27)
				)
				(justify left)
			)
		)
		(property "License" "Apache-2.0"
			(at 182.88 81.28 0)
			(effects
				(font
					(size 1.27 1.27)
					(thickness 0.15)
				)
				(justify left bottom)
				(hide yes)
			)
		)
		(property "Author" "Antmicro"
			(at 185.42 81.28 0)
			(effects
				(font
					(size 1.27 1.27)
					(thickness 0.15)
				)
				(justify left bottom)
				(hide yes)
			)
		)
		(property "Voltage" "25V"
			(at 157.48 66.0462 90)
			(effects
				(font
					(size 1.27 1.27)
				)
				(justify left)
			)
		)
		(property "Dielectric" "X5R"
			(at 190.5 81.28 0)
			(effects
				(font
					(size 1.27 1.27)
				)
				(justify left bottom)
				(hide yes)
			)
		)
		(property "Public" "False"
			(at 193.04 81.28 0)
			(effects
				(font
					(size 1.27 1.27)
				)
				(justify left bottom)
				(hide yes)
			)
		)
		(pin "1"
		)
		(pin "2"
		)
		(instances
			(project "cm4-baseboard"
				(path ""
					(reference "C905")
					(unit 1)
				)
			)
			(project "usb"
				(path ""
					(reference "C905")
					(unit 1)
				)
			)
		)
	)
	(symbol
		(lib_id "antmicroResistors0402:R_100k_0402")
		(at 167.64 195.58 270)
		(unit 1)
		(exclude_from_sim no)
		(in_bom yes)
		(on_board yes)
		(dnp no)
		(fields_autoplaced yes)
		(property "Reference" "R914"
			(at 170.18 196.85 90)
			(effects
				(font
					(size 1.27 1.27)
				)
				(justify left)
			)
		)
		(property "Value" "R_100k_0402"
			(at 163.83 195.58 0)
			(effects
				(font
					(size 1.27 1.27)
					(thickness 0.15)
				)
				(justify left bottom)
				(hide yes)
			)
		)
		(property "Footprint" "antmicro-footprints:R_0402_1005Metric"
			(at 172.72 200.66 0)
			(effects
				(font
					(size 1.27 1.27)
					(thickness 0.15)
				)
				(justify left bottom)
				(hide yes)
			)
		)
		(property "Datasheet" "https://www.bourns.com/docs/product-datasheets/cr.pdf"
			(at 167.64 195.58 0)
			(effects
				(font
					(size 1.27 1.27)
					(thickness 0.15)
				)
				(justify left bottom)
				(hide yes)
			)
		)
		(property "Description" ""
			(at 167.64 195.58 0)
			(effects
				(font
					(size 1.27 1.27)
				)
				(hide yes)
			)
		)
		(property "Manufacturer" "Bourns"
			(at 177.8 200.66 0)
			(effects
				(font
					(size 1.27 1.27)
					(thickness 0.15)
				)
				(justify left bottom)
				(hide yes)
			)
		)
		(property "MPN" "CR0402-FX-1003GLF"
			(at 175.26 200.66 0)
			(effects
				(font
					(size 1.27 1.27)
					(thickness 0.15)
				)
				(justify left bottom)
				(hide yes)
			)
		)
		(property "Val" "100k"
			(at 170.18 199.39 90)
			(effects
				(font
					(size 1.27 1.27)
					(thickness 0.15)
				)
				(justify left)
			)
		)
		(property "License" "Apache-2.0"
			(at 142.24 215.9 0)
			(effects
				(font
					(size 1.27 1.27)
					(thickness 0.15)
				)
				(justify left bottom)
				(hide yes)
			)
		)
		(property "Author" "Antmicro"
			(at 139.7 215.9 0)
			(effects
				(font
					(size 1.27 1.27)
					(thickness 0.15)
				)
				(justify left bottom)
				(hide yes)
			)
		)
		(property "Tolerance" "1%"
			(at 157.48 215.9 0)
			(effects
				(font
					(size 1.27 1.27)
				)
				(justify left bottom)
				(hide yes)
			)
		)
		(pin "1"
		)
		(pin "2"
		)
		(instances
			(project "cm4-baseboard"
				(path ""
					(reference "R914")
					(unit 1)
				)
			)
			(project "usb"
				(path ""
					(reference "R914")
					(unit 1)
				)
			)
		)
	)
	(symbol
		(lib_id "antmicropower:PWR_FLAG")
		(at 293.37 53.34 0)
		(unit 1)
		(exclude_from_sim no)
		(in_bom yes)
		(on_board yes)
		(dnp no)
		(property "Reference" "#FLG012"
			(at 293.37 51.435 0)
			(effects
				(font
					(size 1.27 1.27)
				)
				(hide yes)
			)
		)
		(property "Value" "PWR_FLAG"
			(at 298.45 53.34 0)
			(effects
				(font
					(size 1.27 1.27)
				)
			)
		)
		(property "Footprint" ""
			(at 293.37 53.34 0)
			(effects
				(font
					(size 1.27 1.27)
				)
				(hide yes)
			)
		)
		(property "Datasheet" ""
			(at 293.37 53.34 0)
			(effects
				(font
					(size 1.27 1.27)
				)
				(hide yes)
			)
		)
		(property "Description" ""
			(at 293.37 53.34 0)
			(effects
				(font
					(size 1.27 1.27)
				)
				(hide yes)
			)
		)
		(pin "1"
		)
		(instances
			(project "cm4-baseboard"
				(path ""
					(reference "#FLG012")
					(unit 1)
				)
			)
		)
	)
	(symbol
		(lib_id "antmicroTransistorsFETsMOSFETsSingle:SSM3J332R")
		(at 220.98 190.5 90)
		(unit 1)
		(exclude_from_sim no)
		(in_bom yes)
		(on_board yes)
		(dnp no)
		(fields_autoplaced yes)
		(property "Reference" "Q903"
			(at 218.44 176.53 90)
			(effects
				(font
					(size 1.27 1.27)
					(thickness 0.15)
				)
			)
		)
		(property "Value" "SSM3J332R"
			(at 218.44 179.07 90)
			(effects
				(font
					(size 1.27 1.27)
					(thickness 0.15)
				)
				(hide yes)
			)
		)
		(property "Footprint" "antmicro-footprints:SOT-23-3"
			(at 226.06 176.53 0)
			(effects
				(font
					(size 1.27 1.27)
					(thickness 0.15)
				)
				(justify left bottom)
				(hide yes)
			)
		)
		(property "Datasheet" "https://www.mouser.com/datasheet/2/408/SSM3J332R_datasheet_en_20181015-1150575.pdf"
			(at 228.6 176.53 0)
			(effects
				(font
					(size 1.27 1.27)
					(thickness 0.15)
				)
				(justify left bottom)
				(hide yes)
			)
		)
		(property "Description" ""
			(at 220.98 190.5 0)
			(effects
				(font
					(size 1.27 1.27)
				)
				(hide yes)
			)
		)
		(property "MPN" "SSM3J332R,LF"
			(at 218.44 179.07 90)
			(effects
				(font
					(size 1.27 1.27)
					(thickness 0.15)
				)
			)
		)
		(property "Manufacturer" "Toshiba"
			(at 233.68 176.53 0)
			(effects
				(font
					(size 1.27 1.27)
					(thickness 0.15)
				)
				(justify left bottom)
				(hide yes)
			)
		)
		(property "Author" "Antmicro"
			(at 236.22 176.53 0)
			(effects
				(font
					(size 1.27 1.27)
					(thickness 0.15)
				)
				(justify left bottom)
				(hide yes)
			)
		)
		(property "License" "Apache-2.0"
			(at 238.76 176.53 0)
			(effects
				(font
					(size 1.27 1.27)
					(thickness 0.15)
				)
				(justify left bottom)
				(hide yes)
			)
		)
		(pin "1"
		)
		(pin "2"
		)
		(pin "3"
		)
		(instances
			(project "cm4-baseboard"
				(path ""
					(reference "Q903")
					(unit 1)
				)
			)
			(project "usb"
				(path ""
					(reference "Q903")
					(unit 1)
				)
			)
		)
	)
	(symbol
		(lib_id "antmicroCapacitors0402:C_100n_0402")
		(at 77.47 64.77 270)
		(mirror x)
		(unit 1)
		(exclude_from_sim no)
		(in_bom yes)
		(on_board yes)
		(dnp no)
		(property "Reference" "C902"
			(at 78.74 60.96 90)
			(effects
				(font
					(size 1.27 1.27)
					(thickness 0.15)
				)
				(justify left)
			)
		)
		(property "Value" "C_100n_0402"
			(at 67.31 44.45 0)
			(effects
				(font
					(size 1.27 1.27)
					(thickness 0.15)
				)
				(justify left bottom)
				(hide yes)
			)
		)
		(property "Footprint" "antmicro-footprints:C_0402_1005Metric"
			(at 64.77 44.45 0)
			(effects
				(font
					(size 1.27 1.27)
					(thickness 0.15)
				)
				(justify left bottom)
				(hide yes)
			)
		)
		(property "Datasheet" "https://www.murata.com/products/productdetail?partno=GRM155R61H104KE14%23"
			(at 62.23 44.45 0)
			(effects
				(font
					(size 1.27 1.27)
					(thickness 0.15)
				)
				(justify left bottom)
				(hide yes)
			)
		)
		(property "Description" ""
			(at 77.47 64.77 0)
			(effects
				(font
					(size 1.27 1.27)
				)
				(hide yes)
			)
		)
		(property "MPN" "GRM155R61H104KE14D"
			(at 59.69 44.45 0)
			(effects
				(font
					(size 1.27 1.27)
					(thickness 0.15)
				)
				(justify left bottom)
				(hide yes)
			)
		)
		(property "Manufacturer" "Murata"
			(at 57.15 44.45 0)
			(effects
				(font
					(size 1.27 1.27)
					(thickness 0.15)
				)
				(justify left bottom)
				(hide yes)
			)
		)
		(property "License" "Apache-2.0"
			(at 54.61 44.45 0)
			(effects
				(font
					(size 1.27 1.27)
					(thickness 0.15)
				)
				(justify left bottom)
				(hide yes)
			)
		)
		(property "Author" "Antmicro"
			(at 52.07 44.45 0)
			(effects
				(font
					(size 1.27 1.27)
					(thickness 0.15)
				)
				(justify left bottom)
				(hide yes)
			)
		)
		(property "Val" "100n"
			(at 78.74 63.5 90)
			(effects
				(font
					(size 1.27 1.27)
					(thickness 0.15)
				)
				(justify left)
			)
		)
		(property "Voltage" "50V"
			(at 49.53 44.45 0)
			(effects
				(font
					(size 1.27 1.27)
				)
				(justify left bottom)
				(hide yes)
			)
		)
		(property "Dielectric" "X5R"
			(at 46.99 44.45 0)
			(effects
				(font
					(size 1.27 1.27)
				)
				(justify left bottom)
				(hide yes)
			)
		)
		(pin "1"
		)
		(pin "2"
		)
		(instances
			(project "cm4-baseboard"
				(path ""
					(reference "C902")
					(unit 1)
				)
			)
			(project "usb"
				(path ""
					(reference "C902")
					(unit 1)
				)
			)
		)
	)
	(symbol
		(lib_id "antmicroResistors0402:R_470R_0402")
		(at 243.84 60.96 270)
		(mirror x)
		(unit 1)
		(exclude_from_sim no)
		(in_bom yes)
		(on_board yes)
		(dnp no)
		(fields_autoplaced yes)
		(property "Reference" "R918"
			(at 246.38 57.1499 90)
			(effects
				(font
					(size 1.27 1.27)
				)
				(justify left)
			)
		)
		(property "Value" "R_470R_0402"
			(at 231.14 40.64 0)
			(effects
				(font
					(size 1.27 1.27)
					(thickness 0.15)
				)
				(justify left bottom)
				(hide yes)
			)
		)
		(property "Footprint" "antmicro-footprints:R_0402_1005Metric"
			(at 228.6 40.64 0)
			(effects
				(font
					(size 1.27 1.27)
					(thickness 0.15)
				)
				(justify left bottom)
				(hide yes)
			)
		)
		(property "Datasheet" "https://www.bourns.com/docs/product-datasheets/cr.pdf"
			(at 226.06 40.64 0)
			(effects
				(font
					(size 1.27 1.27)
					(thickness 0.15)
				)
				(justify left bottom)
				(hide yes)
			)
		)
		(property "Description" ""
			(at 243.84 60.96 0)
			(effects
				(font
					(size 1.27 1.27)
				)
				(hide yes)
			)
		)
		(property "Manufacturer" "Bourns"
			(at 220.98 40.64 0)
			(effects
				(font
					(size 1.27 1.27)
					(thickness 0.15)
				)
				(justify left bottom)
				(hide yes)
			)
		)
		(property "MPN" "CR0402-FX-4700GLF"
			(at 223.52 40.64 0)
			(effects
				(font
					(size 1.27 1.27)
					(thickness 0.15)
				)
				(justify left bottom)
				(hide yes)
			)
		)
		(property "Val" "470R"
			(at 246.38 59.6899 90)
			(effects
				(font
					(size 1.27 1.27)
					(thickness 0.15)
				)
				(justify left)
			)
		)
		(property "License" "Apache-2.0"
			(at 218.44 40.64 0)
			(effects
				(font
					(size 1.27 1.27)
					(thickness 0.15)
				)
				(justify left bottom)
				(hide yes)
			)
		)
		(property "Author" "Antmicro"
			(at 215.9 40.64 0)
			(effects
				(font
					(size 1.27 1.27)
					(thickness 0.15)
				)
				(justify left bottom)
				(hide yes)
			)
		)
		(property "Tolerance" "1%"
			(at 233.68 40.64 0)
			(effects
				(font
					(size 1.27 1.27)
				)
				(justify left bottom)
				(hide yes)
			)
		)
		(pin "1"
		)
		(pin "2"
		)
		(instances
			(project "cm4-baseboard"
				(path ""
					(reference "R918")
					(unit 1)
				)
			)
			(project "usb"
				(path ""
					(reference "R918")
					(unit 1)
				)
			)
		)
	)
	(symbol
		(lib_id "antmicroLEDIndicationDiscrete:LED_G_0603_KP-1608CGCK")
		(at 322.58 116.84 270)
		(mirror x)
		(unit 1)
		(exclude_from_sim no)
		(in_bom yes)
		(on_board yes)
		(dnp no)
		(property "Reference" "D912"
			(at 328.93 113.03 90)
			(effects
				(font
					(size 1.27 1.27)
					(thickness 0.15)
				)
			)
		)
		(property "Value" "LED_G_0603_KP-1608CGCK"
			(at 314.96 93.98 0)
			(effects
				(font
					(size 1.27 1.27)
					(thickness 0.15)
				)
				(justify left bottom)
				(hide yes)
			)
		)
		(property "Footprint" "antmicro-footprints:LED_0603_1608Metric_G"
			(at 312.42 93.98 0)
			(effects
				(font
					(size 1.27 1.27)
					(thickness 0.15)
				)
				(justify left bottom)
				(hide yes)
			)
		)
		(property "Datasheet" "http://www.kingbright.com/attachments/file/psearch//000/00/00/KP-1608CGCK(Ver.23B).pdf"
			(at 309.88 93.98 0)
			(effects
				(font
					(size 1.27 1.27)
					(thickness 0.15)
				)
				(justify left bottom)
				(hide yes)
			)
		)
		(property "Description" ""
			(at 322.58 116.84 0)
			(effects
				(font
					(size 1.27 1.27)
				)
				(hide yes)
			)
		)
		(property "MPN" "KP-1608CGCK"
			(at 307.34 93.98 0)
			(effects
				(font
					(size 1.27 1.27)
					(thickness 0.15)
				)
				(justify left bottom)
				(hide yes)
			)
		)
		(property "Manufacturer" "Kingbright"
			(at 304.8 93.98 0)
			(effects
				(font
					(size 1.27 1.27)
					(thickness 0.15)
				)
				(justify left bottom)
				(hide yes)
			)
		)
		(property "Color" "Green"
			(at 328.93 115.57 90)
			(effects
				(font
					(size 1.27 1.27)
				)
			)
		)
		(property "Author" "Antmicro"
			(at 302.26 93.98 0)
			(effects
				(font
					(size 1.27 1.27)
					(thickness 0.15)
				)
				(justify left bottom)
				(hide yes)
			)
		)
		(property "License" "Apache-2.0"
			(at 299.72 93.98 0)
			(effects
				(font
					(size 1.27 1.27)
					(thickness 0.15)
				)
				(justify left bottom)
				(hide yes)
			)
		)
		(pin "2"
		)
		(pin "1"
		)
		(instances
			(project "cm4-baseboard"
				(path ""
					(reference "D912")
					(unit 1)
				)
			)
		)
	)
	(symbol
		(lib_id "antmicropower:GND")
		(at 168.91 68.58 0)
		(unit 1)
		(exclude_from_sim no)
		(in_bom yes)
		(on_board yes)
		(dnp no)
		(fields_autoplaced yes)
		(property "Reference" "#PWR0920"
			(at 177.8 71.12 0)
			(effects
				(font
					(size 1.27 1.27)
					(thickness 0.15)
				)
				(justify left bottom)
				(hide yes)
			)
		)
		(property "Value" "GND"
			(at 166.8998 73.66 0)
			(effects
				(font
					(size 1.27 1.27)
					(thickness 0.15)
				)
				(justify left bottom)
			)
		)
		(property "Footprint" ""
			(at 177.8 76.2 0)
			(effects
				(font
					(size 1.27 1.27)
					(thickness 0.15)
				)
				(justify left bottom)
				(hide yes)
			)
		)
		(property "Datasheet" ""
			(at 177.8 81.28 0)
			(effects
				(font
					(size 1.27 1.27)
					(thickness 0.15)
				)
				(justify left bottom)
				(hide yes)
			)
		)
		(property "Description" ""
			(at 168.91 68.58 0)
			(effects
				(font
					(size 1.27 1.27)
				)
				(hide yes)
			)
		)
		(property "Author" "Antmicro"
			(at 177.8 76.2 0)
			(effects
				(font
					(size 1.27 1.27)
					(thickness 0.15)
				)
				(justify left bottom)
				(hide yes)
			)
		)
		(property "License" "Apache-2.0"
			(at 177.8 78.74 0)
			(effects
				(font
					(size 1.27 1.27)
					(thickness 0.15)
				)
				(justify left bottom)
				(hide yes)
			)
		)
		(pin "1"
		)
		(instances
			(project "cm4-baseboard"
				(path ""
					(reference "#PWR0920")
					(unit 1)
				)
			)
			(project "usb"
				(path ""
					(reference "#PWR0920")
					(unit 1)
				)
			)
		)
	)
	(symbol
		(lib_id "antmicroLEDIndicationDiscrete:LED_G_0603_KP-1608CGCK")
		(at 100.33 210.82 270)
		(mirror x)
		(unit 1)
		(exclude_from_sim no)
		(in_bom yes)
		(on_board yes)
		(dnp no)
		(property "Reference" "D905"
			(at 105.41 207.01 90)
			(effects
				(font
					(size 1.27 1.27)
					(thickness 0.15)
				)
			)
		)
		(property "Value" "LED_G_0603_KP-1608CGCK"
			(at 92.71 187.96 0)
			(effects
				(font
					(size 1.27 1.27)
					(thickness 0.15)
				)
				(justify left bottom)
				(hide yes)
			)
		)
		(property "Footprint" "antmicro-footprints:LED_0603_1608Metric_G"
			(at 90.17 187.96 0)
			(effects
				(font
					(size 1.27 1.27)
					(thickness 0.15)
				)
				(justify left bottom)
				(hide yes)
			)
		)
		(property "Datasheet" "http://www.kingbright.com/attachments/file/psearch//000/00/00/KP-1608CGCK(Ver.23B).pdf"
			(at 87.63 187.96 0)
			(effects
				(font
					(size 1.27 1.27)
					(thickness 0.15)
				)
				(justify left bottom)
				(hide yes)
			)
		)
		(property "Description" ""
			(at 100.33 210.82 0)
			(effects
				(font
					(size 1.27 1.27)
				)
				(hide yes)
			)
		)
		(property "MPN" "KP-1608CGCK"
			(at 85.09 187.96 0)
			(effects
				(font
					(size 1.27 1.27)
					(thickness 0.15)
				)
				(justify left bottom)
				(hide yes)
			)
		)
		(property "Manufacturer" "Kingbright"
			(at 82.55 187.96 0)
			(effects
				(font
					(size 1.27 1.27)
					(thickness 0.15)
				)
				(justify left bottom)
				(hide yes)
			)
		)
		(property "Color" "Green"
			(at 105.41 209.55 90)
			(effects
				(font
					(size 1.27 1.27)
				)
			)
		)
		(property "Author" "Antmicro"
			(at 80.01 187.96 0)
			(effects
				(font
					(size 1.27 1.27)
					(thickness 0.15)
				)
				(justify left bottom)
				(hide yes)
			)
		)
		(property "License" "Apache-2.0"
			(at 77.47 187.96 0)
			(effects
				(font
					(size 1.27 1.27)
					(thickness 0.15)
				)
				(justify left bottom)
				(hide yes)
			)
		)
		(pin "2"
		)
		(pin "1"
		)
		(instances
			(project "cm4-baseboard"
				(path ""
					(reference "D905")
					(unit 1)
				)
			)
		)
	)
	(symbol
		(lib_id "antmicroTestPoints:TP_0.75mm_SMD")
		(at 370.84 153.67 0)
		(mirror x)
		(unit 1)
		(exclude_from_sim no)
		(in_bom no)
		(on_board yes)
		(dnp no)
		(property "Reference" "TP908"
			(at 375.285 153.67 0)
			(effects
				(font
					(size 1.27 1.27)
				)
				(justify left)
			)
		)
		(property "Value" "TP_0.75mm_SMD"
			(at 370.84 151.13 0)
			(effects
				(font
					(size 1.27 1.27)
					(thickness 0.15)
				)
				(justify left bottom)
				(hide yes)
			)
		)
		(property "Footprint" "antmicro-footprints:TP_SMD_0.75mm"
			(at 375.92 158.75 0)
			(effects
				(font
					(size 1.27 1.27)
					(thickness 0.15)
				)
				(justify left bottom)
				(hide yes)
			)
		)
		(property "Datasheet" ""
			(at 375.92 161.29 0)
			(effects
				(font
					(size 1.27 1.27)
					(thickness 0.15)
				)
				(justify left bottom)
				(hide yes)
			)
		)
		(property "Description" ""
			(at 370.84 153.67 0)
			(effects
				(font
					(size 1.27 1.27)
				)
				(hide yes)
			)
		)
		(property "MPN" ""
			(at 370.84 153.67 0)
			(effects
				(font
					(size 1.27 1.27)
					(thickness 0.15)
				)
				(justify left bottom)
				(hide yes)
			)
		)
		(property "Manufacturer" ""
			(at 370.84 153.67 0)
			(effects
				(font
					(size 1.27 1.27)
					(thickness 0.15)
				)
				(justify left bottom)
				(hide yes)
			)
		)
		(property "Author" "Antmicro"
			(at 386.08 138.43 0)
			(effects
				(font
					(size 1.27 1.27)
					(thickness 0.15)
				)
				(justify left bottom)
				(hide yes)
			)
		)
		(property "License" "Apache-2.0"
			(at 386.08 135.89 0)
			(effects
				(font
					(size 1.27 1.27)
					(thickness 0.15)
				)
				(justify left bottom)
				(hide yes)
			)
		)
		(pin "1"
		)
		(instances
			(project "cm4-baseboard"
				(path ""
					(reference "TP908")
					(unit 1)
				)
			)
			(project "usb"
				(path ""
					(reference "TP908")
					(unit 1)
				)
			)
		)
	)
	(symbol
		(lib_id "antmicropower:GND")
		(at 274.32 45.72 0)
		(unit 1)
		(exclude_from_sim no)
		(in_bom yes)
		(on_board yes)
		(dnp no)
		(property "Reference" "#PWR0938"
			(at 274.32 52.07 0)
			(effects
				(font
					(size 1.27 1.27)
				)
				(hide yes)
			)
		)
		(property "Value" "GND"
			(at 274.32 49.53 0)
			(effects
				(font
					(size 1.27 1.27)
				)
			)
		)
		(property "Footprint" ""
			(at 283.21 53.34 0)
			(effects
				(font
					(size 1.27 1.27)
					(thickness 0.15)
				)
				(justify left bottom)
				(hide yes)
			)
		)
		(property "Datasheet" ""
			(at 283.21 58.42 0)
			(effects
				(font
					(size 1.27 1.27)
					(thickness 0.15)
				)
				(justify left bottom)
				(hide yes)
			)
		)
		(property "Description" ""
			(at 274.32 45.72 0)
			(effects
				(font
					(size 1.27 1.27)
				)
				(hide yes)
			)
		)
		(property "Author" "Antmicro"
			(at 283.21 53.34 0)
			(effects
				(font
					(size 1.27 1.27)
					(thickness 0.15)
				)
				(justify left bottom)
				(hide yes)
			)
		)
		(property "License" "Apache-2.0"
			(at 283.21 55.88 0)
			(effects
				(font
					(size 1.27 1.27)
					(thickness 0.15)
				)
				(justify left bottom)
				(hide yes)
			)
		)
		(pin "1"
		)
		(instances
			(project "cm4-baseboard"
				(path ""
					(reference "#PWR0938")
					(unit 1)
				)
			)
			(project "usb"
				(path ""
					(reference "#PWR0938")
					(unit 1)
				)
			)
		)
	)
	(symbol
		(lib_id "antmicroCapacitors0402:C_100n_0402")
		(at 270.51 149.86 270)
		(unit 1)
		(exclude_from_sim no)
		(in_bom yes)
		(on_board yes)
		(dnp no)
		(property "Reference" "C914"
			(at 271.145 150.495 90)
			(effects
				(font
					(size 1.27 1.27)
				)
				(justify left)
			)
		)
		(property "Value" "C_100n_0402"
			(at 266.7 149.86 0)
			(effects
				(font
					(size 1.27 1.27)
					(thickness 0.15)
				)
				(justify left bottom)
				(hide yes)
			)
		)
		(property "Footprint" "antmicro-footprints:C_0402_1005Metric"
			(at 275.59 154.94 0)
			(effects
				(font
					(size 1.27 1.27)
					(thickness 0.15)
				)
				(justify left bottom)
				(hide yes)
			)
		)
		(property "Datasheet" "https://www.murata.com/products/productdetail?partno=GRM155R61H104KE14%23"
			(at 270.51 149.86 0)
			(effects
				(font
					(size 1.27 1.27)
					(thickness 0.15)
				)
				(justify left bottom)
				(hide yes)
			)
		)
		(property "Description" ""
			(at 270.51 149.86 0)
			(effects
				(font
					(size 1.27 1.27)
				)
				(hide yes)
			)
		)
		(property "Manufacturer" "Murata"
			(at 280.67 154.94 0)
			(effects
				(font
					(size 1.27 1.27)
					(thickness 0.15)
				)
				(justify left bottom)
				(hide yes)
			)
		)
		(property "MPN" "GRM155R61H104KE14D"
			(at 278.13 154.94 0)
			(effects
				(font
					(size 1.27 1.27)
					(thickness 0.15)
				)
				(justify left bottom)
				(hide yes)
			)
		)
		(property "Val" "100n"
			(at 271.145 154.305 90)
			(effects
				(font
					(size 1.27 1.27)
					(thickness 0.15)
				)
				(justify left)
			)
		)
		(property "License" "Apache-2.0"
			(at 247.65 170.18 0)
			(effects
				(font
					(size 1.27 1.27)
					(thickness 0.15)
				)
				(justify left bottom)
				(hide yes)
			)
		)
		(property "Author" "Antmicro"
			(at 245.11 170.18 0)
			(effects
				(font
					(size 1.27 1.27)
					(thickness 0.15)
				)
				(justify left bottom)
				(hide yes)
			)
		)
		(property "Voltage" "50V"
			(at 242.57 170.18 0)
			(effects
				(font
					(size 1.27 1.27)
				)
				(justify left bottom)
				(hide yes)
			)
		)
		(property "Dielectric" "X5R"
			(at 240.03 170.18 0)
			(effects
				(font
					(size 1.27 1.27)
				)
				(justify left bottom)
				(hide yes)
			)
		)
		(pin "1"
		)
		(pin "2"
		)
		(instances
			(project "cm4-baseboard"
				(path ""
					(reference "C914")
					(unit 1)
				)
			)
			(project "usb"
				(path ""
					(reference "C914")
					(unit 1)
				)
			)
		)
	)
	(symbol
		(lib_id "antmicropower:GND")
		(at 147.32 142.24 0)
		(unit 1)
		(exclude_from_sim no)
		(in_bom yes)
		(on_board yes)
		(dnp no)
		(fields_autoplaced yes)
		(property "Reference" "#PWR0914"
			(at 147.32 148.59 0)
			(effects
				(font
					(size 1.27 1.27)
				)
				(hide yes)
			)
		)
		(property "Value" "GND"
			(at 147.32 147.32 0)
			(effects
				(font
					(size 1.27 1.27)
				)
			)
		)
		(property "Footprint" ""
			(at 156.21 149.86 0)
			(effects
				(font
					(size 1.27 1.27)
					(thickness 0.15)
				)
				(justify left bottom)
				(hide yes)
			)
		)
		(property "Datasheet" ""
			(at 156.21 154.94 0)
			(effects
				(font
					(size 1.27 1.27)
					(thickness 0.15)
				)
				(justify left bottom)
				(hide yes)
			)
		)
		(property "Description" ""
			(at 147.32 142.24 0)
			(effects
				(font
					(size 1.27 1.27)
				)
				(hide yes)
			)
		)
		(property "Author" "Antmicro"
			(at 156.21 149.86 0)
			(effects
				(font
					(size 1.27 1.27)
					(thickness 0.15)
				)
				(justify left bottom)
				(hide yes)
			)
		)
		(property "License" "Apache-2.0"
			(at 156.21 152.4 0)
			(effects
				(font
					(size 1.27 1.27)
					(thickness 0.15)
				)
				(justify left bottom)
				(hide yes)
			)
		)
		(pin "1"
		)
		(instances
			(project "cm4-baseboard"
				(path ""
					(reference "#PWR0914")
					(unit 1)
				)
			)
			(project "usb"
				(path ""
					(reference "#PWR0914")
					(unit 1)
				)
			)
		)
	)
	(symbol
		(lib_id "antmicroResistors0402:R_2k2_0402")
		(at 332.74 110.49 90)
		(unit 1)
		(exclude_from_sim no)
		(in_bom yes)
		(on_board yes)
		(dnp no)
		(property "Reference" "R923"
			(at 334.01 106.68 90)
			(effects
				(font
					(size 1.27 1.27)
					(thickness 0.15)
				)
				(justify right)
			)
		)
		(property "Value" "R_2k2_0402"
			(at 345.44 90.17 0)
			(effects
				(font
					(size 1.27 1.27)
					(thickness 0.15)
				)
				(justify left bottom)
				(hide yes)
			)
		)
		(property "Footprint" "antmicro-footprints:R_0402_1005Metric"
			(at 347.98 90.17 0)
			(effects
				(font
					(size 1.27 1.27)
					(thickness 0.15)
				)
				(justify left bottom)
				(hide yes)
			)
		)
		(property "Datasheet" "https://www.bourns.com/docs/product-datasheets/cr.pdf"
			(at 350.52 90.17 0)
			(effects
				(font
					(size 1.27 1.27)
					(thickness 0.15)
				)
				(justify left bottom)
				(hide yes)
			)
		)
		(property "Description" ""
			(at 332.74 110.49 0)
			(effects
				(font
					(size 1.27 1.27)
				)
				(hide yes)
			)
		)
		(property "MPN" "CR0402-FX-2201GLF"
			(at 353.06 90.17 0)
			(effects
				(font
					(size 1.27 1.27)
					(thickness 0.15)
				)
				(justify left bottom)
				(hide yes)
			)
		)
		(property "Manufacturer" "Bourns"
			(at 355.6 90.17 0)
			(effects
				(font
					(size 1.27 1.27)
					(thickness 0.15)
				)
				(justify left bottom)
				(hide yes)
			)
		)
		(property "License" "Apache-2.0"
			(at 358.14 90.17 0)
			(effects
				(font
					(size 1.27 1.27)
					(thickness 0.15)
				)
				(justify left bottom)
				(hide yes)
			)
		)
		(property "Author" "Antmicro"
			(at 360.68 90.17 0)
			(effects
				(font
					(size 1.27 1.27)
					(thickness 0.15)
				)
				(justify left bottom)
				(hide yes)
			)
		)
		(property "Val" "2k2"
			(at 334.01 109.22 90)
			(effects
				(font
					(size 1.27 1.27)
					(thickness 0.15)
				)
				(justify right)
			)
		)
		(property "Tolerance" "1%"
			(at 342.9 90.17 0)
			(effects
				(font
					(size 1.27 1.27)
				)
				(justify left bottom)
				(hide yes)
			)
		)
		(pin "1"
		)
		(pin "2"
		)
		(instances
			(project "cm4-baseboard"
				(path ""
					(reference "R923")
					(unit 1)
				)
			)
			(project "usb"
				(path ""
					(reference "R923")
					(unit 1)
				)
			)
		)
	)
	(symbol
		(lib_id "antmicropower:GND")
		(at 198.12 194.31 0)
		(mirror y)
		(unit 1)
		(exclude_from_sim no)
		(in_bom yes)
		(on_board yes)
		(dnp no)
		(fields_autoplaced yes)
		(property "Reference" "#PWR016"
			(at 198.12 200.66 0)
			(effects
				(font
					(size 1.27 1.27)
				)
				(justify left bottom)
				(hide yes)
			)
		)
		(property "Value" "GND"
			(at 198.12 199.39 0)
			(effects
				(font
					(size 1.27 1.27)
				)
			)
		)
		(property "Footprint" ""
			(at 189.23 201.93 0)
			(effects
				(font
					(size 1.27 1.27)
					(thickness 0.15)
				)
				(justify left bottom)
				(hide yes)
			)
		)
		(property "Datasheet" ""
			(at 189.23 207.01 0)
			(effects
				(font
					(size 1.27 1.27)
					(thickness 0.15)
				)
				(justify left bottom)
				(hide yes)
			)
		)
		(property "Description" ""
			(at 198.12 194.31 0)
			(effects
				(font
					(size 1.27 1.27)
				)
				(hide yes)
			)
		)
		(property "Author" "Antmicro"
			(at 189.23 201.93 0)
			(effects
				(font
					(size 1.27 1.27)
					(thickness 0.15)
				)
				(justify left bottom)
				(hide yes)
			)
		)
		(property "License" "Apache-2.0"
			(at 189.23 204.47 0)
			(effects
				(font
					(size 1.27 1.27)
					(thickness 0.15)
				)
				(justify left bottom)
				(hide yes)
			)
		)
		(pin "1"
		)
		(instances
			(project "cm4-baseboard"
				(path ""
					(reference "#PWR016")
					(unit 1)
				)
			)
			(project "usb"
				(path ""
					(reference "#PWR016")
					(unit 1)
				)
			)
		)
	)
	(symbol
		(lib_id "antmicropower:GND")
		(at 63.5 245.11 0)
		(unit 1)
		(exclude_from_sim no)
		(in_bom yes)
		(on_board yes)
		(dnp no)
		(fields_autoplaced yes)
		(property "Reference" "#PWR0903"
			(at 72.39 247.65 0)
			(effects
				(font
					(size 1.27 1.27)
					(thickness 0.15)
				)
				(justify left bottom)
				(hide yes)
			)
		)
		(property "Value" "GND"
			(at 61.4898 250.19 0)
			(effects
				(font
					(size 1.27 1.27)
					(thickness 0.15)
				)
				(justify left bottom)
			)
		)
		(property "Footprint" ""
			(at 72.39 252.73 0)
			(effects
				(font
					(size 1.27 1.27)
					(thickness 0.15)
				)
				(justify left bottom)
				(hide yes)
			)
		)
		(property "Datasheet" ""
			(at 72.39 257.81 0)
			(effects
				(font
					(size 1.27 1.27)
					(thickness 0.15)
				)
				(justify left bottom)
				(hide yes)
			)
		)
		(property "Description" ""
			(at 63.5 245.11 0)
			(effects
				(font
					(size 1.27 1.27)
				)
				(hide yes)
			)
		)
		(property "Author" "Antmicro"
			(at 72.39 252.73 0)
			(effects
				(font
					(size 1.27 1.27)
					(thickness 0.15)
				)
				(justify left bottom)
				(hide yes)
			)
		)
		(property "License" "Apache-2.0"
			(at 72.39 255.27 0)
			(effects
				(font
					(size 1.27 1.27)
					(thickness 0.15)
				)
				(justify left bottom)
				(hide yes)
			)
		)
		(pin "1"
		)
		(instances
			(project "cm4-baseboard"
				(path ""
					(reference "#PWR0903")
					(unit 1)
				)
			)
			(project "usb"
				(path ""
					(reference "#PWR0903")
					(unit 1)
				)
			)
		)
	)
	(symbol
		(lib_id "antmicroResistors0402:R_10k_0402")
		(at 168.91 59.69 270)
		(mirror x)
		(unit 1)
		(exclude_from_sim no)
		(in_bom yes)
		(on_board yes)
		(dnp no)
		(property "Reference" "R909"
			(at 167.64 55.88 90)
			(effects
				(font
					(size 1.27 1.27)
					(thickness 0.15)
				)
				(justify right)
			)
		)
		(property "Value" "R_10k_0402"
			(at 156.21 39.37 0)
			(effects
				(font
					(size 1.27 1.27)
					(thickness 0.15)
				)
				(justify left bottom)
				(hide yes)
			)
		)
		(property "Footprint" "antmicro-footprints:R_0402_1005Metric"
			(at 153.67 39.37 0)
			(effects
				(font
					(size 1.27 1.27)
					(thickness 0.15)
				)
				(justify left bottom)
				(hide yes)
			)
		)
		(property "Datasheet" "https://www.bourns.com/docs/product-datasheets/cr.pdf"
			(at 151.13 39.37 0)
			(effects
				(font
					(size 1.27 1.27)
					(thickness 0.15)
				)
				(justify left bottom)
				(hide yes)
			)
		)
		(property "Description" ""
			(at 168.91 59.69 0)
			(effects
				(font
					(size 1.27 1.27)
				)
				(hide yes)
			)
		)
		(property "Manufacturer" "Bourns"
			(at 146.05 39.37 0)
			(effects
				(font
					(size 1.27 1.27)
					(thickness 0.15)
				)
				(justify left bottom)
				(hide yes)
			)
		)
		(property "MPN" "CR0402-FX-1002GLF"
			(at 148.59 39.37 0)
			(effects
				(font
					(size 1.27 1.27)
					(thickness 0.15)
				)
				(justify left bottom)
				(hide yes)
			)
		)
		(property "Val" "10k"
			(at 167.64 58.42 90)
			(effects
				(font
					(size 1.27 1.27)
					(thickness 0.15)
				)
				(justify right)
			)
		)
		(property "License" "Apache-2.0"
			(at 143.51 39.37 0)
			(effects
				(font
					(size 1.27 1.27)
					(thickness 0.15)
				)
				(justify left bottom)
				(hide yes)
			)
		)
		(property "Author" "Antmicro"
			(at 140.97 39.37 0)
			(effects
				(font
					(size 1.27 1.27)
					(thickness 0.15)
				)
				(justify left bottom)
				(hide yes)
			)
		)
		(property "Tolerance" "1%"
			(at 158.75 39.37 0)
			(effects
				(font
					(size 1.27 1.27)
				)
				(justify left bottom)
				(hide yes)
			)
		)
		(pin "1"
		)
		(pin "2"
		)
		(instances
			(project "cm4-baseboard"
				(path ""
					(reference "R909")
					(unit 1)
				)
			)
			(project "usb"
				(path ""
					(reference "R909")
					(unit 1)
				)
			)
		)
	)
	(symbol
		(lib_id "antmicroCapacitors0402:C_100n_0402")
		(at 121.92 243.84 270)
		(unit 1)
		(exclude_from_sim no)
		(in_bom yes)
		(on_board yes)
		(dnp no)
		(property "Reference" "C928"
			(at 123.19 245.11 90)
			(effects
				(font
					(size 1.27 1.27)
				)
				(justify left)
			)
		)
		(property "Value" "C_100n_0402"
			(at 111.76 264.16 0)
			(effects
				(font
					(size 1.27 1.27)
					(thickness 0.15)
				)
				(justify left bottom)
				(hide yes)
			)
		)
		(property "Footprint" "antmicro-footprints:C_0402_1005Metric"
			(at 109.22 264.16 0)
			(effects
				(font
					(size 1.27 1.27)
					(thickness 0.15)
				)
				(justify left bottom)
				(hide yes)
			)
		)
		(property "Datasheet" "https://www.murata.com/products/productdetail?partno=GRM155R61H104KE14%23"
			(at 106.68 264.16 0)
			(effects
				(font
					(size 1.27 1.27)
					(thickness 0.15)
				)
				(justify left bottom)
				(hide yes)
			)
		)
		(property "Description" ""
			(at 121.92 243.84 0)
			(effects
				(font
					(size 1.27 1.27)
				)
				(hide yes)
			)
		)
		(property "Manufacturer" "Murata"
			(at 101.6 264.16 0)
			(effects
				(font
					(size 1.27 1.27)
					(thickness 0.15)
				)
				(justify left bottom)
				(hide yes)
			)
		)
		(property "MPN" "GRM155R61H104KE14D"
			(at 104.14 264.16 0)
			(effects
				(font
					(size 1.27 1.27)
					(thickness 0.15)
				)
				(justify left bottom)
				(hide yes)
			)
		)
		(property "Val" "100n"
			(at 123.19 247.65 90)
			(effects
				(font
					(size 1.27 1.27)
					(thickness 0.15)
				)
				(justify left)
			)
		)
		(property "License" "Apache-2.0"
			(at 99.06 264.16 0)
			(effects
				(font
					(size 1.27 1.27)
					(thickness 0.15)
				)
				(justify left bottom)
				(hide yes)
			)
		)
		(property "Author" "Antmicro"
			(at 96.52 264.16 0)
			(effects
				(font
					(size 1.27 1.27)
					(thickness 0.15)
				)
				(justify left bottom)
				(hide yes)
			)
		)
		(property "Voltage" "50V"
			(at 93.98 264.16 0)
			(effects
				(font
					(size 1.27 1.27)
				)
				(justify left bottom)
				(hide yes)
			)
		)
		(property "Dielectric" "X5R"
			(at 91.44 264.16 0)
			(effects
				(font
					(size 1.27 1.27)
				)
				(justify left bottom)
				(hide yes)
			)
		)
		(pin "1"
		)
		(pin "2"
		)
		(instances
			(project "cm4-baseboard"
				(path ""
					(reference "C928")
					(unit 1)
				)
			)
			(project "usb"
				(path ""
					(reference "C928")
					(unit 1)
				)
			)
		)
	)
	(symbol
		(lib_id "antmicropower:GND")
		(at 384.81 170.18 0)
		(unit 1)
		(exclude_from_sim no)
		(in_bom yes)
		(on_board yes)
		(dnp no)
		(property "Reference" "#PWR025"
			(at 393.7 172.72 0)
			(effects
				(font
					(size 1.27 1.27)
					(thickness 0.15)
				)
				(justify left bottom)
				(hide yes)
			)
		)
		(property "Value" "GND"
			(at 384.81 174.625 0)
			(effects
				(font
					(size 1.27 1.27)
					(thickness 0.15)
				)
			)
		)
		(property "Footprint" ""
			(at 393.7 177.8 0)
			(effects
				(font
					(size 1.27 1.27)
					(thickness 0.15)
				)
				(justify left bottom)
				(hide yes)
			)
		)
		(property "Datasheet" ""
			(at 393.7 182.88 0)
			(effects
				(font
					(size 1.27 1.27)
					(thickness 0.15)
				)
				(justify left bottom)
				(hide yes)
			)
		)
		(property "Description" ""
			(at 384.81 170.18 0)
			(effects
				(font
					(size 1.27 1.27)
				)
				(hide yes)
			)
		)
		(property "Author" "Antmicro"
			(at 393.7 177.8 0)
			(effects
				(font
					(size 1.27 1.27)
					(thickness 0.15)
				)
				(justify left bottom)
				(hide yes)
			)
		)
		(property "License" "Apache-2.0"
			(at 393.7 180.34 0)
			(effects
				(font
					(size 1.27 1.27)
					(thickness 0.15)
				)
				(justify left bottom)
				(hide yes)
			)
		)
		(pin "1"
		)
		(instances
			(project "cm4-baseboard"
				(path ""
					(reference "#PWR025")
					(unit 1)
				)
			)
		)
	)
	(symbol
		(lib_id "antmicroPMICPowerDistributionSwitchesLoadDrivers:AP22615A_TSOT26")
		(at 149.86 196.85 0)
		(mirror y)
		(unit 1)
		(exclude_from_sim no)
		(in_bom yes)
		(on_board yes)
		(dnp no)
		(fields_autoplaced yes)
		(property "Reference" "U901"
			(at 142.24 189.23 0)
			(effects
				(font
					(size 1.27 1.27)
				)
			)
		)
		(property "Value" "AP22615A_TSOT26"
			(at 142.24 191.77 0)
			(effects
				(font
					(size 1.27 1.27)
					(thickness 0.15)
				)
				(hide yes)
			)
		)
		(property "Footprint" "antmicro-footprints:TSOT23-6"
			(at 119.38 204.47 0)
			(effects
				(font
					(size 1.27 1.27)
					(thickness 0.15)
				)
				(justify left bottom)
				(hide yes)
			)
		)
		(property "Datasheet" "https://www.mouser.com/datasheet/2/115/DIOD_S_A0008958405_1-2543193.pdf"
			(at 119.38 207.01 0)
			(effects
				(font
					(size 1.27 1.27)
					(thickness 0.15)
				)
				(justify left bottom)
				(hide yes)
			)
		)
		(property "Description" ""
			(at 149.86 196.85 0)
			(effects
				(font
					(size 1.27 1.27)
				)
				(hide yes)
			)
		)
		(property "MPN" "AP22615AWU-7"
			(at 142.24 191.77 0)
			(effects
				(font
					(size 1.27 1.27)
					(thickness 0.15)
				)
			)
		)
		(property "Manufacturer" "Diodes Incorporated"
			(at 119.38 212.09 0)
			(effects
				(font
					(size 1.27 1.27)
					(thickness 0.15)
				)
				(justify left bottom)
				(hide yes)
			)
		)
		(property "Author" "Antmicro"
			(at 119.38 214.63 0)
			(effects
				(font
					(size 1.27 1.27)
					(thickness 0.15)
				)
				(justify left bottom)
				(hide yes)
			)
		)
		(property "License" "Apache-2.0"
			(at 119.38 217.17 0)
			(effects
				(font
					(size 1.27 1.27)
					(thickness 0.15)
				)
				(justify left bottom)
				(hide yes)
			)
		)
		(pin "1"
		)
		(pin "2"
		)
		(pin "3"
		)
		(pin "4"
		)
		(pin "5"
		)
		(pin "6"
		)
		(instances
			(project "cm4-baseboard"
				(path ""
					(reference "U901")
					(unit 1)
				)
			)
			(project "usb"
				(path ""
					(reference "U901")
					(unit 1)
				)
			)
		)
	)
	(symbol
		(lib_id "antmicroResistors0402:R_1k_0402")
		(at 100.33 203.2 90)
		(unit 1)
		(exclude_from_sim no)
		(in_bom yes)
		(on_board yes)
		(dnp no)
		(fields_autoplaced yes)
		(property "Reference" "R901"
			(at 102.87 199.39 90)
			(effects
				(font
					(size 1.27 1.27)
					(thickness 0.15)
				)
				(justify right)
			)
		)
		(property "Value" "R_1k_0402"
			(at 113.03 182.88 0)
			(effects
				(font
					(size 1.27 1.27)
					(thickness 0.15)
				)
				(justify left bottom)
				(hide yes)
			)
		)
		(property "Footprint" "antmicro-footprints:R_0402_1005Metric"
			(at 115.57 182.88 0)
			(effects
				(font
					(size 1.27 1.27)
					(thickness 0.15)
				)
				(justify left bottom)
				(hide yes)
			)
		)
		(property "Datasheet" "https://www.bourns.com/docs/product-datasheets/cr.pdf"
			(at 118.11 182.88 0)
			(effects
				(font
					(size 1.27 1.27)
					(thickness 0.15)
				)
				(justify left bottom)
				(hide yes)
			)
		)
		(property "Description" ""
			(at 100.33 203.2 0)
			(effects
				(font
					(size 1.27 1.27)
				)
				(hide yes)
			)
		)
		(property "MPN" "CR0402-FX-1001GLF"
			(at 120.65 182.88 0)
			(effects
				(font
					(size 1.27 1.27)
					(thickness 0.15)
				)
				(justify left bottom)
				(hide yes)
			)
		)
		(property "Manufacturer" "Bourns"
			(at 123.19 182.88 0)
			(effects
				(font
					(size 1.27 1.27)
					(thickness 0.15)
				)
				(justify left bottom)
				(hide yes)
			)
		)
		(property "License" "Apache-2.0"
			(at 125.73 182.88 0)
			(effects
				(font
					(size 1.27 1.27)
					(thickness 0.15)
				)
				(justify left bottom)
				(hide yes)
			)
		)
		(property "Author" "Antmicro"
			(at 128.27 182.88 0)
			(effects
				(font
					(size 1.27 1.27)
					(thickness 0.15)
				)
				(justify left bottom)
				(hide yes)
			)
		)
		(property "Val" "1k"
			(at 102.87 201.93 90)
			(effects
				(font
					(size 1.27 1.27)
					(thickness 0.15)
				)
				(justify right)
			)
		)
		(property "Tolerance" "1%"
			(at 110.49 182.88 0)
			(effects
				(font
					(size 1.27 1.27)
				)
				(justify left bottom)
				(hide yes)
			)
		)
		(pin "1"
		)
		(pin "2"
		)
		(instances
			(project "cm4-baseboard"
				(path ""
					(reference "R901")
					(unit 1)
				)
			)
		)
	)
	(symbol
		(lib_id "antmicroResistors0402:R_4k7_0402")
		(at 130.81 205.74 90)
		(unit 1)
		(exclude_from_sim no)
		(in_bom yes)
		(on_board yes)
		(dnp no)
		(fields_autoplaced yes)
		(property "Reference" "R905"
			(at 128.27 201.93 90)
			(effects
				(font
					(size 1.27 1.27)
				)
				(justify left)
			)
		)
		(property "Value" "R_4k7_0402"
			(at 143.51 185.42 0)
			(effects
				(font
					(size 1.27 1.27)
					(thickness 0.15)
				)
				(justify left bottom)
				(hide yes)
			)
		)
		(property "Footprint" "antmicro-footprints:R_0402_1005Metric"
			(at 146.05 185.42 0)
			(effects
				(font
					(size 1.27 1.27)
					(thickness 0.15)
				)
				(justify left bottom)
				(hide yes)
			)
		)
		(property "Datasheet" "https://www.bourns.com/docs/product-datasheets/cr.pdf"
			(at 148.59 185.42 0)
			(effects
				(font
					(size 1.27 1.27)
					(thickness 0.15)
				)
				(justify left bottom)
				(hide yes)
			)
		)
		(property "Description" ""
			(at 130.81 205.74 0)
			(effects
				(font
					(size 1.27 1.27)
				)
				(hide yes)
			)
		)
		(property "Manufacturer" "Bourns"
			(at 153.67 185.42 0)
			(effects
				(font
					(size 1.27 1.27)
					(thickness 0.15)
				)
				(justify left bottom)
				(hide yes)
			)
		)
		(property "MPN" "CR0402-FX-4701GLF"
			(at 151.13 185.42 0)
			(effects
				(font
					(size 1.27 1.27)
					(thickness 0.15)
				)
				(justify left bottom)
				(hide yes)
			)
		)
		(property "Val" "4k7"
			(at 128.27 204.47 90)
			(effects
				(font
					(size 1.27 1.27)
					(thickness 0.15)
				)
				(justify left)
			)
		)
		(property "License" "Apache-2.0"
			(at 156.21 185.42 0)
			(effects
				(font
					(size 1.27 1.27)
					(thickness 0.15)
				)
				(justify left bottom)
				(hide yes)
			)
		)
		(property "Author" "Antmicro"
			(at 158.75 185.42 0)
			(effects
				(font
					(size 1.27 1.27)
					(thickness 0.15)
				)
				(justify left bottom)
				(hide yes)
			)
		)
		(property "Tolerance" "1%"
			(at 140.97 185.42 0)
			(effects
				(font
					(size 1.27 1.27)
				)
				(justify left bottom)
				(hide yes)
			)
		)
		(pin "1"
		)
		(pin "2"
		)
		(instances
			(project "cm4-baseboard"
				(path ""
					(reference "R905")
					(unit 1)
				)
			)
			(project "usb"
				(path ""
					(reference "R905")
					(unit 1)
				)
			)
		)
	)
	(symbol
		(lib_id "antmicropower:PWR_FLAG")
		(at 200.66 182.88 0)
		(unit 1)
		(exclude_from_sim no)
		(in_bom yes)
		(on_board yes)
		(dnp no)
		(property "Reference" "#FLG01"
			(at 200.66 180.975 0)
			(effects
				(font
					(size 1.27 1.27)
				)
				(hide yes)
			)
		)
		(property "Value" "PWR_FLAG"
			(at 200.66 179.07 0)
			(effects
				(font
					(size 1.27 1.27)
				)
			)
		)
		(property "Footprint" ""
			(at 200.66 182.88 0)
			(effects
				(font
					(size 1.27 1.27)
				)
				(hide yes)
			)
		)
		(property "Datasheet" ""
			(at 200.66 182.88 0)
			(effects
				(font
					(size 1.27 1.27)
				)
				(hide yes)
			)
		)
		(property "Description" ""
			(at 200.66 182.88 0)
			(effects
				(font
					(size 1.27 1.27)
				)
				(hide yes)
			)
		)
		(pin "1"
		)
		(instances
			(project "cm4-baseboard"
				(path ""
					(reference "#FLG01")
					(unit 1)
				)
			)
		)
	)
	(symbol
		(lib_id "antmicropower:GND")
		(at 85.09 207.01 0)
		(unit 1)
		(exclude_from_sim no)
		(in_bom yes)
		(on_board yes)
		(dnp no)
		(fields_autoplaced yes)
		(property "Reference" "#PWR0907"
			(at 93.98 209.55 0)
			(effects
				(font
					(size 1.27 1.27)
					(thickness 0.15)
				)
				(justify left bottom)
				(hide yes)
			)
		)
		(property "Value" "GND"
			(at 83.0798 212.09 0)
			(effects
				(font
					(size 1.27 1.27)
					(thickness 0.15)
				)
				(justify left bottom)
			)
		)
		(property "Footprint" ""
			(at 93.98 214.63 0)
			(effects
				(font
					(size 1.27 1.27)
					(thickness 0.15)
				)
				(justify left bottom)
				(hide yes)
			)
		)
		(property "Datasheet" ""
			(at 93.98 219.71 0)
			(effects
				(font
					(size 1.27 1.27)
					(thickness 0.15)
				)
				(justify left bottom)
				(hide yes)
			)
		)
		(property "Description" ""
			(at 85.09 207.01 0)
			(effects
				(font
					(size 1.27 1.27)
				)
				(hide yes)
			)
		)
		(property "Author" "Antmicro"
			(at 93.98 214.63 0)
			(effects
				(font
					(size 1.27 1.27)
					(thickness 0.15)
				)
				(justify left bottom)
				(hide yes)
			)
		)
		(property "License" "Apache-2.0"
			(at 93.98 217.17 0)
			(effects
				(font
					(size 1.27 1.27)
					(thickness 0.15)
				)
				(justify left bottom)
				(hide yes)
			)
		)
		(pin "1"
		)
		(instances
			(project "cm4-baseboard"
				(path ""
					(reference "#PWR0907")
					(unit 1)
				)
			)
			(project "usb"
				(path ""
					(reference "#PWR0907")
					(unit 1)
				)
			)
		)
	)
	(symbol
		(lib_id "antmicroCapacitors0402:C_100n_0402")
		(at 266.7 39.37 270)
		(unit 1)
		(exclude_from_sim no)
		(in_bom yes)
		(on_board yes)
		(dnp no)
		(property "Reference" "C913"
			(at 267.335 40.005 90)
			(effects
				(font
					(size 1.27 1.27)
				)
				(justify left)
			)
		)
		(property "Value" "C_100n_0402"
			(at 262.89 39.37 0)
			(effects
				(font
					(size 1.27 1.27)
					(thickness 0.15)
				)
				(justify left bottom)
				(hide yes)
			)
		)
		(property "Footprint" "antmicro-footprints:C_0402_1005Metric"
			(at 271.78 44.45 0)
			(effects
				(font
					(size 1.27 1.27)
					(thickness 0.15)
				)
				(justify left bottom)
				(hide yes)
			)
		)
		(property "Datasheet" "https://www.murata.com/products/productdetail?partno=GRM155R61H104KE14%23"
			(at 266.7 39.37 0)
			(effects
				(font
					(size 1.27 1.27)
					(thickness 0.15)
				)
				(justify left bottom)
				(hide yes)
			)
		)
		(property "Description" ""
			(at 266.7 39.37 0)
			(effects
				(font
					(size 1.27 1.27)
				)
				(hide yes)
			)
		)
		(property "Manufacturer" "Murata"
			(at 276.86 44.45 0)
			(effects
				(font
					(size 1.27 1.27)
					(thickness 0.15)
				)
				(justify left bottom)
				(hide yes)
			)
		)
		(property "MPN" "GRM155R61H104KE14D"
			(at 274.32 44.45 0)
			(effects
				(font
					(size 1.27 1.27)
					(thickness 0.15)
				)
				(justify left bottom)
				(hide yes)
			)
		)
		(property "Val" "100n"
			(at 267.335 43.815 90)
			(effects
				(font
					(size 1.27 1.27)
					(thickness 0.15)
				)
				(justify left)
			)
		)
		(property "License" "Apache-2.0"
			(at 243.84 59.69 0)
			(effects
				(font
					(size 1.27 1.27)
					(thickness 0.15)
				)
				(justify left bottom)
				(hide yes)
			)
		)
		(property "Author" "Antmicro"
			(at 241.3 59.69 0)
			(effects
				(font
					(size 1.27 1.27)
					(thickness 0.15)
				)
				(justify left bottom)
				(hide yes)
			)
		)
		(property "Voltage" "50V"
			(at 238.76 59.69 0)
			(effects
				(font
					(size 1.27 1.27)
				)
				(justify left bottom)
				(hide yes)
			)
		)
		(property "Dielectric" "X5R"
			(at 236.22 59.69 0)
			(effects
				(font
					(size 1.27 1.27)
				)
				(justify left bottom)
				(hide yes)
			)
		)
		(pin "1"
		)
		(pin "2"
		)
		(instances
			(project "cm4-baseboard"
				(path ""
					(reference "C913")
					(unit 1)
				)
			)
			(project "usb"
				(path ""
					(reference "C913")
					(unit 1)
				)
			)
		)
	)
	(symbol
		(lib_id "antmicroUSBConnectors:USB-C_GCT_USB4105-GF-A")
		(at 38.1 58.42 0)
		(unit 1)
		(exclude_from_sim no)
		(in_bom yes)
		(on_board yes)
		(dnp no)
		(fields_autoplaced yes)
		(property "Reference" "J902"
			(at 24.765 50.8 0)
			(effects
				(font
					(size 1.27 1.27)
					(thickness 0.15)
				)
			)
		)
		(property "Value" "USB-C_GCT_USB4105-GF-A"
			(at 24.765 53.34 0)
			(effects
				(font
					(size 1.27 1.27)
					(thickness 0.15)
				)
				(hide yes)
			)
		)
		(property "Footprint" "antmicro-footprints:USB-C_Receptacle_GCT_USB4105-GF-A"
			(at 76.2 66.04 0)
			(effects
				(font
					(size 1.27 1.27)
					(thickness 0.15)
				)
				(justify left bottom)
				(hide yes)
			)
		)
		(property "Datasheet" "https://gct.co/files/drawings/usb4105.pdf"
			(at 76.2 68.58 0)
			(effects
				(font
					(size 1.27 1.27)
					(thickness 0.15)
				)
				(justify left bottom)
				(hide yes)
			)
		)
		(property "Description" ""
			(at 38.1 58.42 0)
			(effects
				(font
					(size 1.27 1.27)
				)
				(hide yes)
			)
		)
		(property "Manufacturer" "GCT"
			(at 76.2 71.12 0)
			(effects
				(font
					(size 1.27 1.27)
					(thickness 0.15)
				)
				(justify left bottom)
				(hide yes)
			)
		)
		(property "MPN" "USB4105-GF-A"
			(at 24.765 53.34 0)
			(effects
				(font
					(size 1.27 1.27)
					(thickness 0.15)
				)
			)
		)
		(property "Author" "Antmicro"
			(at 76.2 76.2 0)
			(effects
				(font
					(size 1.27 1.27)
					(thickness 0.15)
				)
				(justify left bottom)
				(hide yes)
			)
		)
		(property "License" "Apache-2.0"
			(at 76.2 78.74 0)
			(effects
				(font
					(size 1.27 1.27)
					(thickness 0.15)
				)
				(justify left bottom)
				(hide yes)
			)
		)
		(pin "A1"
		)
		(pin "A12"
		)
		(pin "A4"
		)
		(pin "A5"
		)
		(pin "A6"
		)
		(pin "A7"
		)
		(pin "A8"
		)
		(pin "A9"
		)
		(pin "B1"
		)
		(pin "B12"
		)
		(pin "B4"
		)
		(pin "B5"
		)
		(pin "B6"
		)
		(pin "B7"
		)
		(pin "B8"
		)
		(pin "B9"
		)
		(pin "SH"
		)
		(instances
			(project "cm4-baseboard"
				(path ""
					(reference "J902")
					(unit 1)
				)
			)
			(project "usb"
				(path ""
					(reference "J902")
					(unit 1)
				)
			)
		)
	)
	(symbol
		(lib_id "antmicroTestPoints:TP_0.75mm_SMD")
		(at 370.84 135.89 0)
		(mirror x)
		(unit 1)
		(exclude_from_sim no)
		(in_bom no)
		(on_board yes)
		(dnp no)
		(property "Reference" "TP904"
			(at 375.285 135.89 0)
			(effects
				(font
					(size 1.27 1.27)
				)
				(justify left)
			)
		)
		(property "Value" "TP_0.75mm_SMD"
			(at 370.84 133.35 0)
			(effects
				(font
					(size 1.27 1.27)
					(thickness 0.15)
				)
				(justify left bottom)
				(hide yes)
			)
		)
		(property "Footprint" "antmicro-footprints:TP_SMD_0.75mm"
			(at 375.92 140.97 0)
			(effects
				(font
					(size 1.27 1.27)
					(thickness 0.15)
				)
				(justify left bottom)
				(hide yes)
			)
		)
		(property "Datasheet" ""
			(at 375.92 143.51 0)
			(effects
				(font
					(size 1.27 1.27)
					(thickness 0.15)
				)
				(justify left bottom)
				(hide yes)
			)
		)
		(property "Description" ""
			(at 370.84 135.89 0)
			(effects
				(font
					(size 1.27 1.27)
				)
				(hide yes)
			)
		)
		(property "MPN" ""
			(at 370.84 135.89 0)
			(effects
				(font
					(size 1.27 1.27)
					(thickness 0.15)
				)
				(justify left bottom)
				(hide yes)
			)
		)
		(property "Manufacturer" ""
			(at 370.84 135.89 0)
			(effects
				(font
					(size 1.27 1.27)
					(thickness 0.15)
				)
				(justify left bottom)
				(hide yes)
			)
		)
		(property "Author" "Antmicro"
			(at 386.08 120.65 0)
			(effects
				(font
					(size 1.27 1.27)
					(thickness 0.15)
				)
				(justify left bottom)
				(hide yes)
			)
		)
		(property "License" "Apache-2.0"
			(at 386.08 118.11 0)
			(effects
				(font
					(size 1.27 1.27)
					(thickness 0.15)
				)
				(justify left bottom)
				(hide yes)
			)
		)
		(pin "1"
		)
		(instances
			(project "cm4-baseboard"
				(path ""
					(reference "TP904")
					(unit 1)
				)
			)
		)
	)
	(symbol
		(lib_id "antmicroCapacitors0402:C_100n_0402")
		(at 289.56 71.12 270)
		(unit 1)
		(exclude_from_sim no)
		(in_bom yes)
		(on_board yes)
		(dnp no)
		(fields_autoplaced yes)
		(property "Reference" "C920"
			(at 292.1 72.3963 90)
			(effects
				(font
					(size 1.27 1.27)
				)
				(justify left)
			)
		)
		(property "Value" "C_100n_0402"
			(at 285.75 71.12 0)
			(effects
				(font
					(size 1.27 1.27)
					(thickness 0.15)
				)
				(justify left bottom)
				(hide yes)
			)
		)
		(property "Footprint" "antmicro-footprints:C_0402_1005Metric"
			(at 294.64 76.2 0)
			(effects
				(font
					(size 1.27 1.27)
					(thickness 0.15)
				)
				(justify left bottom)
				(hide yes)
			)
		)
		(property "Datasheet" "https://www.murata.com/products/productdetail?partno=GRM155R61H104KE14%23"
			(at 289.56 71.12 0)
			(effects
				(font
					(size 1.27 1.27)
					(thickness 0.15)
				)
				(justify left bottom)
				(hide yes)
			)
		)
		(property "Description" ""
			(at 289.56 71.12 0)
			(effects
				(font
					(size 1.27 1.27)
				)
				(hide yes)
			)
		)
		(property "Manufacturer" "Murata"
			(at 299.72 76.2 0)
			(effects
				(font
					(size 1.27 1.27)
					(thickness 0.15)
				)
				(justify left bottom)
				(hide yes)
			)
		)
		(property "MPN" "GRM155R61H104KE14D"
			(at 297.18 76.2 0)
			(effects
				(font
					(size 1.27 1.27)
					(thickness 0.15)
				)
				(justify left bottom)
				(hide yes)
			)
		)
		(property "Val" "100n"
			(at 292.1 75.5712 90)
			(effects
				(font
					(size 1.27 1.27)
					(thickness 0.15)
				)
				(justify left)
			)
		)
		(property "License" "Apache-2.0"
			(at 266.7 91.44 0)
			(effects
				(font
					(size 1.27 1.27)
					(thickness 0.15)
				)
				(justify left bottom)
				(hide yes)
			)
		)
		(property "Author" "Antmicro"
			(at 264.16 91.44 0)
			(effects
				(font
					(size 1.27 1.27)
					(thickness 0.15)
				)
				(justify left bottom)
				(hide yes)
			)
		)
		(property "Voltage" "50V"
			(at 261.62 91.44 0)
			(effects
				(font
					(size 1.27 1.27)
				)
				(justify left bottom)
				(hide yes)
			)
		)
		(property "Dielectric" "X5R"
			(at 259.08 91.44 0)
			(effects
				(font
					(size 1.27 1.27)
				)
				(justify left bottom)
				(hide yes)
			)
		)
		(pin "1"
		)
		(pin "2"
		)
		(instances
			(project "cm4-baseboard"
				(path ""
					(reference "C920")
					(unit 1)
				)
			)
			(project "usb"
				(path ""
					(reference "C920")
					(unit 1)
				)
			)
		)
	)
	(symbol
		(lib_id "antmicropower:GND")
		(at 39.37 236.22 0)
		(unit 1)
		(exclude_from_sim no)
		(in_bom yes)
		(on_board yes)
		(dnp no)
		(fields_autoplaced yes)
		(property "Reference" "#PWR0901"
			(at 48.26 238.76 0)
			(effects
				(font
					(size 1.27 1.27)
					(thickness 0.15)
				)
				(justify left bottom)
				(hide yes)
			)
		)
		(property "Value" "GND"
			(at 37.3598 241.3 0)
			(effects
				(font
					(size 1.27 1.27)
					(thickness 0.15)
				)
				(justify left bottom)
			)
		)
		(property "Footprint" ""
			(at 48.26 243.84 0)
			(effects
				(font
					(size 1.27 1.27)
					(thickness 0.15)
				)
				(justify left bottom)
				(hide yes)
			)
		)
		(property "Datasheet" ""
			(at 48.26 248.92 0)
			(effects
				(font
					(size 1.27 1.27)
					(thickness 0.15)
				)
				(justify left bottom)
				(hide yes)
			)
		)
		(property "Description" ""
			(at 39.37 236.22 0)
			(effects
				(font
					(size 1.27 1.27)
				)
				(hide yes)
			)
		)
		(property "Author" "Antmicro"
			(at 48.26 243.84 0)
			(effects
				(font
					(size 1.27 1.27)
					(thickness 0.15)
				)
				(justify left bottom)
				(hide yes)
			)
		)
		(property "License" "Apache-2.0"
			(at 48.26 246.38 0)
			(effects
				(font
					(size 1.27 1.27)
					(thickness 0.15)
				)
				(justify left bottom)
				(hide yes)
			)
		)
		(pin "1"
		)
		(instances
			(project "cm4-baseboard"
				(path ""
					(reference "#PWR0901")
					(unit 1)
				)
			)
			(project "usb"
				(path ""
					(reference "#PWR0901")
					(unit 1)
				)
			)
		)
	)
	(symbol
		(lib_id "antmicroTestPoints:TP_0.75mm_SMD")
		(at 262.89 144.78 90)
		(unit 1)
		(exclude_from_sim no)
		(in_bom no)
		(on_board yes)
		(dnp no)
		(fields_autoplaced yes)
		(property "Reference" "TP905"
			(at 264.795 141.6049 90)
			(effects
				(font
					(size 1.27 1.27)
				)
				(justify right)
			)
		)
		(property "Value" "TP_0.75mm_SMD"
			(at 265.43 144.78 0)
			(effects
				(font
					(size 1.27 1.27)
					(thickness 0.15)
				)
				(justify left bottom)
				(hide yes)
			)
		)
		(property "Footprint" "antmicro-footprints:TP_SMD_0.75mm"
			(at 257.81 139.7 0)
			(effects
				(font
					(size 1.27 1.27)
					(thickness 0.15)
				)
				(justify left bottom)
				(hide yes)
			)
		)
		(property "Datasheet" ""
			(at 255.27 139.7 0)
			(effects
				(font
					(size 1.27 1.27)
					(thickness 0.15)
				)
				(justify left bottom)
				(hide yes)
			)
		)
		(property "Description" ""
			(at 262.89 144.78 0)
			(effects
				(font
					(size 1.27 1.27)
				)
				(hide yes)
			)
		)
		(property "MPN" ""
			(at 262.89 144.78 0)
			(effects
				(font
					(size 1.27 1.27)
					(thickness 0.15)
				)
				(justify left bottom)
				(hide yes)
			)
		)
		(property "Manufacturer" ""
			(at 262.89 144.78 0)
			(effects
				(font
					(size 1.27 1.27)
					(thickness 0.15)
				)
				(justify left bottom)
				(hide yes)
			)
		)
		(property "Author" "Antmicro"
			(at 278.13 129.54 0)
			(effects
				(font
					(size 1.27 1.27)
					(thickness 0.15)
				)
				(justify left bottom)
				(hide yes)
			)
		)
		(property "License" "Apache-2.0"
			(at 280.67 129.54 0)
			(effects
				(font
					(size 1.27 1.27)
					(thickness 0.15)
				)
				(justify left bottom)
				(hide yes)
			)
		)
		(pin "1"
		)
		(instances
			(project "cm4-baseboard"
				(path ""
					(reference "TP905")
					(unit 1)
				)
			)
			(project "usb"
				(path ""
					(reference "TP905")
					(unit 1)
				)
			)
		)
	)
	(symbol
		(lib_id "antmicropower:GND")
		(at 121.92 250.19 0)
		(unit 1)
		(exclude_from_sim no)
		(in_bom yes)
		(on_board yes)
		(dnp no)
		(property "Reference" "#PWR015"
			(at 121.92 256.54 0)
			(effects
				(font
					(size 1.27 1.27)
				)
				(justify left bottom)
				(hide yes)
			)
		)
		(property "Value" "GND"
			(at 118.11 251.46 0)
			(effects
				(font
					(size 1.27 1.27)
				)
			)
		)
		(property "Footprint" ""
			(at 121.92 250.19 0)
			(effects
				(font
					(size 1.27 1.27)
				)
				(hide yes)
			)
		)
		(property "Datasheet" ""
			(at 121.92 250.19 0)
			(effects
				(font
					(size 1.27 1.27)
				)
				(hide yes)
			)
		)
		(property "Description" ""
			(at 121.92 250.19 0)
			(effects
				(font
					(size 1.27 1.27)
				)
				(hide yes)
			)
		)
		(property "Author" "Antmicro"
			(at 130.81 257.81 0)
			(effects
				(font
					(size 1.27 1.27)
					(thickness 0.15)
				)
				(justify left bottom)
				(hide yes)
			)
		)
		(property "License" "Apache-2.0"
			(at 130.81 260.35 0)
			(effects
				(font
					(size 1.27 1.27)
					(thickness 0.15)
				)
				(justify left bottom)
				(hide yes)
			)
		)
		(pin "1"
		)
		(instances
			(project "cm4-baseboard"
				(path ""
					(reference "#PWR015")
					(unit 1)
				)
			)
			(project "usb"
				(path ""
					(reference "#PWR015")
					(unit 1)
				)
			)
		)
	)
	(symbol
		(lib_id "antmicroFerriteBeadsandChips:FB_120Z_1.3A_Murata-BLM15PD_0402")
		(at 269.24 54.61 0)
		(unit 1)
		(exclude_from_sim no)
		(in_bom yes)
		(on_board yes)
		(dnp no)
		(property "Reference" "FB902"
			(at 271.78 58.42 0)
			(effects
				(font
					(size 1.27 1.27)
				)
			)
		)
		(property "Value" "FB_120Z_1.3A_Murata-BLM15PD_0402"
			(at 271.7419 48.26 0)
			(effects
				(font
					(size 1.27 1.27)
					(thickness 0.15)
				)
				(hide yes)
			)
		)
		(property "Footprint" "antmicro-footprints:FB_0402_1005Metric"
			(at 283.21 62.23 0)
			(effects
				(font
					(size 1.27 1.27)
					(thickness 0.15)
				)
				(justify left bottom)
				(hide yes)
			)
		)
		(property "Datasheet" "https://www.murata.com/en-us/products/productdata/8796740059166/ENFA0018.pdf"
			(at 283.21 64.77 0)
			(effects
				(font
					(size 1.27 1.27)
					(thickness 0.15)
				)
				(justify left bottom)
				(hide yes)
			)
		)
		(property "Description" ""
			(at 269.24 54.61 0)
			(effects
				(font
					(size 1.27 1.27)
				)
				(hide yes)
			)
		)
		(property "MPN" "BLM15PD121SN1D"
			(at 283.21 67.31 0)
			(effects
				(font
					(size 1.27 1.27)
					(thickness 0.15)
				)
				(justify left bottom)
				(hide yes)
			)
		)
		(property "Manufacturer" "Murata"
			(at 283.21 69.85 0)
			(effects
				(font
					(size 1.27 1.27)
					(thickness 0.15)
				)
				(justify left bottom)
				(hide yes)
			)
		)
		(property "Author" "Antmicro"
			(at 283.21 72.39 0)
			(effects
				(font
					(size 1.27 1.27)
					(thickness 0.15)
				)
				(justify left bottom)
				(hide yes)
			)
		)
		(property "License" "Apache-2.0"
			(at 283.21 74.93 0)
			(effects
				(font
					(size 1.27 1.27)
					(thickness 0.15)
				)
				(justify left bottom)
				(hide yes)
			)
		)
		(property "Val" "120Z/1.3A"
			(at 271.78 60.96 0)
			(effects
				(font
					(size 1.27 1.27)
				)
			)
		)
		(property "Current" ""
			(at 289.56 77.47 0)
			(effects
				(font
					(size 1.27 1.27)
					(thickness 0.15)
				)
				(justify left bottom)
				(hide yes)
			)
		)
		(pin "1"
		)
		(pin "2"
		)
		(instances
			(project "cm4-baseboard"
				(path ""
					(reference "FB902")
					(unit 1)
				)
			)
			(project "usb"
				(path ""
					(reference "FB902")
					(unit 1)
				)
			)
		)
	)
	(symbol
		(lib_id "antmicroCapacitors0402:C_100n_0402")
		(at 372.11 168.91 90)
		(unit 1)
		(exclude_from_sim no)
		(in_bom yes)
		(on_board yes)
		(dnp no)
		(property "Reference" "C933"
			(at 373.38 163.83 90)
			(effects
				(font
					(size 1.27 1.27)
					(thickness 0.15)
				)
				(justify right)
			)
		)
		(property "Value" "C_100n_0402"
			(at 382.27 148.59 0)
			(effects
				(font
					(size 1.27 1.27)
					(thickness 0.15)
				)
				(justify left bottom)
				(hide yes)
			)
		)
		(property "Footprint" "antmicro-footprints:C_0402_1005Metric"
			(at 384.81 148.59 0)
			(effects
				(font
					(size 1.27 1.27)
					(thickness 0.15)
				)
				(justify left bottom)
				(hide yes)
			)
		)
		(property "Datasheet" "https://www.murata.com/products/productdetail?partno=GRM155R61H104KE14%23"
			(at 387.35 148.59 0)
			(effects
				(font
					(size 1.27 1.27)
					(thickness 0.15)
				)
				(justify left bottom)
				(hide yes)
			)
		)
		(property "Description" ""
			(at 372.11 168.91 0)
			(effects
				(font
					(size 1.27 1.27)
				)
				(hide yes)
			)
		)
		(property "MPN" "GRM155R61H104KE14D"
			(at 389.89 148.59 0)
			(effects
				(font
					(size 1.27 1.27)
					(thickness 0.15)
				)
				(justify left bottom)
				(hide yes)
			)
		)
		(property "Manufacturer" "Murata"
			(at 392.43 148.59 0)
			(effects
				(font
					(size 1.27 1.27)
					(thickness 0.15)
				)
				(justify left bottom)
				(hide yes)
			)
		)
		(property "License" "Apache-2.0"
			(at 394.97 148.59 0)
			(effects
				(font
					(size 1.27 1.27)
					(thickness 0.15)
				)
				(justify left bottom)
				(hide yes)
			)
		)
		(property "Author" "Antmicro"
			(at 397.51 148.59 0)
			(effects
				(font
					(size 1.27 1.27)
					(thickness 0.15)
				)
				(justify left bottom)
				(hide yes)
			)
		)
		(property "Val" "100n"
			(at 373.38 168.91 90)
			(effects
				(font
					(size 1.27 1.27)
					(thickness 0.15)
				)
				(justify right)
			)
		)
		(property "Voltage" "50V"
			(at 400.05 148.59 0)
			(effects
				(font
					(size 1.27 1.27)
				)
				(justify left bottom)
				(hide yes)
			)
		)
		(property "Dielectric" "X5R"
			(at 402.59 148.59 0)
			(effects
				(font
					(size 1.27 1.27)
				)
				(justify left bottom)
				(hide yes)
			)
		)
		(pin "1"
		)
		(pin "2"
		)
		(instances
			(project "cm4-baseboard"
				(path ""
					(reference "C933")
					(unit 1)
				)
			)
		)
	)
	(symbol
		(lib_id "antmicroTestPoints:TP_0.75mm_SMD")
		(at 80.01 195.58 90)
		(unit 1)
		(exclude_from_sim no)
		(in_bom no)
		(on_board yes)
		(dnp no)
		(property "Reference" "TP921"
			(at 77.47 190.5 90)
			(effects
				(font
					(size 1.27 1.27)
				)
				(justify right)
			)
		)
		(property "Value" "TP_0.75mm_SMD"
			(at 82.55 195.58 0)
			(effects
				(font
					(size 1.27 1.27)
					(thickness 0.15)
				)
				(justify left bottom)
				(hide yes)
			)
		)
		(property "Footprint" "antmicro-footprints:TP_SMD_0.75mm"
			(at 74.93 190.5 0)
			(effects
				(font
					(size 1.27 1.27)
					(thickness 0.15)
				)
				(justify left bottom)
				(hide yes)
			)
		)
		(property "Datasheet" ""
			(at 72.39 190.5 0)
			(effects
				(font
					(size 1.27 1.27)
					(thickness 0.15)
				)
				(justify left bottom)
				(hide yes)
			)
		)
		(property "Description" ""
			(at 80.01 195.58 0)
			(effects
				(font
					(size 1.27 1.27)
				)
				(hide yes)
			)
		)
		(property "MPN" ""
			(at 80.01 195.58 0)
			(effects
				(font
					(size 1.27 1.27)
					(thickness 0.15)
				)
				(justify left bottom)
				(hide yes)
			)
		)
		(property "Manufacturer" ""
			(at 80.01 195.58 0)
			(effects
				(font
					(size 1.27 1.27)
					(thickness 0.15)
				)
				(justify left bottom)
				(hide yes)
			)
		)
		(property "Author" "Antmicro"
			(at 95.25 180.34 0)
			(effects
				(font
					(size 1.27 1.27)
					(thickness 0.15)
				)
				(justify left bottom)
				(hide yes)
			)
		)
		(property "License" "Apache-2.0"
			(at 97.79 180.34 0)
			(effects
				(font
					(size 1.27 1.27)
					(thickness 0.15)
				)
				(justify left bottom)
				(hide yes)
			)
		)
		(pin "1"
		)
		(instances
			(project "cm4-baseboard"
				(path ""
					(reference "TP921")
					(unit 1)
				)
			)
		)
	)
	(symbol
		(lib_id "antmicroCapacitors0402:C_100n_0402")
		(at 293.37 149.86 270)
		(unit 1)
		(exclude_from_sim no)
		(in_bom yes)
		(on_board yes)
		(dnp no)
		(property "Reference" "C923"
			(at 294.005 150.495 90)
			(effects
				(font
					(size 1.27 1.27)
				)
				(justify left)
			)
		)
		(property "Value" "C_100n_0402"
			(at 289.56 149.86 0)
			(effects
				(font
					(size 1.27 1.27)
					(thickness 0.15)
				)
				(justify left bottom)
				(hide yes)
			)
		)
		(property "Footprint" "antmicro-footprints:C_0402_1005Metric"
			(at 298.45 154.94 0)
			(effects
				(font
					(size 1.27 1.27)
					(thickness 0.15)
				)
				(justify left bottom)
				(hide yes)
			)
		)
		(property "Datasheet" "https://www.murata.com/products/productdetail?partno=GRM155R61H104KE14%23"
			(at 293.37 149.86 0)
			(effects
				(font
					(size 1.27 1.27)
					(thickness 0.15)
				)
				(justify left bottom)
				(hide yes)
			)
		)
		(property "Description" ""
			(at 293.37 149.86 0)
			(effects
				(font
					(size 1.27 1.27)
				)
				(hide yes)
			)
		)
		(property "Manufacturer" "Murata"
			(at 303.53 154.94 0)
			(effects
				(font
					(size 1.27 1.27)
					(thickness 0.15)
				)
				(justify left bottom)
				(hide yes)
			)
		)
		(property "MPN" "GRM155R61H104KE14D"
			(at 300.99 154.94 0)
			(effects
				(font
					(size 1.27 1.27)
					(thickness 0.15)
				)
				(justify left bottom)
				(hide yes)
			)
		)
		(property "Val" "100n"
			(at 294.005 154.305 90)
			(effects
				(font
					(size 1.27 1.27)
					(thickness 0.15)
				)
				(justify left)
			)
		)
		(property "License" "Apache-2.0"
			(at 270.51 170.18 0)
			(effects
				(font
					(size 1.27 1.27)
					(thickness 0.15)
				)
				(justify left bottom)
				(hide yes)
			)
		)
		(property "Author" "Antmicro"
			(at 267.97 170.18 0)
			(effects
				(font
					(size 1.27 1.27)
					(thickness 0.15)
				)
				(justify left bottom)
				(hide yes)
			)
		)
		(property "Voltage" "50V"
			(at 265.43 170.18 0)
			(effects
				(font
					(size 1.27 1.27)
				)
				(justify left bottom)
				(hide yes)
			)
		)
		(property "Dielectric" "X5R"
			(at 262.89 170.18 0)
			(effects
				(font
					(size 1.27 1.27)
				)
				(justify left bottom)
				(hide yes)
			)
		)
		(pin "1"
		)
		(pin "2"
		)
		(instances
			(project "cm4-baseboard"
				(path ""
					(reference "C923")
					(unit 1)
				)
			)
			(project "usb"
				(path ""
					(reference "C923")
					(unit 1)
				)
			)
		)
	)
	(symbol
		(lib_id "antmicroFerriteBeadsandChips:FB_120Z_1.3A_Murata-BLM15PD_0402")
		(at 279.4 69.85 0)
		(unit 1)
		(exclude_from_sim no)
		(in_bom yes)
		(on_board yes)
		(dnp no)
		(property "Reference" "FB903"
			(at 281.9781 73.66 0)
			(effects
				(font
					(size 1.27 1.27)
				)
			)
		)
		(property "Value" "FB_120Z_1.3A_Murata-BLM15PD_0402"
			(at 281.9019 63.5 0)
			(effects
				(font
					(size 1.27 1.27)
					(thickness 0.15)
				)
				(hide yes)
			)
		)
		(property "Footprint" "antmicro-footprints:FB_0402_1005Metric"
			(at 293.37 77.47 0)
			(effects
				(font
					(size 1.27 1.27)
					(thickness 0.15)
				)
				(justify left bottom)
				(hide yes)
			)
		)
		(property "Datasheet" "https://www.murata.com/en-us/products/productdata/8796740059166/ENFA0018.pdf"
			(at 293.37 80.01 0)
			(effects
				(font
					(size 1.27 1.27)
					(thickness 0.15)
				)
				(justify left bottom)
				(hide yes)
			)
		)
		(property "Description" ""
			(at 279.4 69.85 0)
			(effects
				(font
					(size 1.27 1.27)
				)
				(hide yes)
			)
		)
		(property "MPN" "BLM15PD121SN1D"
			(at 293.37 82.55 0)
			(effects
				(font
					(size 1.27 1.27)
					(thickness 0.15)
				)
				(justify left bottom)
				(hide yes)
			)
		)
		(property "Manufacturer" "Murata"
			(at 293.37 85.09 0)
			(effects
				(font
					(size 1.27 1.27)
					(thickness 0.15)
				)
				(justify left bottom)
				(hide yes)
			)
		)
		(property "Author" "Antmicro"
			(at 293.37 87.63 0)
			(effects
				(font
					(size 1.27 1.27)
					(thickness 0.15)
				)
				(justify left bottom)
				(hide yes)
			)
		)
		(property "License" "Apache-2.0"
			(at 293.37 90.17 0)
			(effects
				(font
					(size 1.27 1.27)
					(thickness 0.15)
				)
				(justify left bottom)
				(hide yes)
			)
		)
		(property "Val" "120Z/1.3A"
			(at 281.94 76.2 0)
			(effects
				(font
					(size 1.27 1.27)
				)
			)
		)
		(property "Current" ""
			(at 299.72 92.71 0)
			(effects
				(font
					(size 1.27 1.27)
					(thickness 0.15)
				)
				(justify left bottom)
				(hide yes)
			)
		)
		(pin "1"
		)
		(pin "2"
		)
		(instances
			(project "cm4-baseboard"
				(path ""
					(reference "FB903")
					(unit 1)
				)
			)
			(project "usb"
				(path ""
					(reference "FB903")
					(unit 1)
				)
			)
		)
	)
	(symbol
		(lib_id "antmicroTestPoints:TP_0.75mm_SMD")
		(at 161.29 262.89 0)
		(mirror x)
		(unit 1)
		(exclude_from_sim no)
		(in_bom no)
		(on_board yes)
		(dnp no)
		(property "Reference" "TP910"
			(at 165.1 262.89 0)
			(effects
				(font
					(size 1.27 1.27)
				)
				(justify left)
			)
		)
		(property "Value" "TP_0.75mm_SMD"
			(at 161.29 260.35 0)
			(effects
				(font
					(size 1.27 1.27)
					(thickness 0.15)
				)
				(justify left bottom)
				(hide yes)
			)
		)
		(property "Footprint" "antmicro-footprints:TP_SMD_0.75mm"
			(at 166.37 267.97 0)
			(effects
				(font
					(size 1.27 1.27)
					(thickness 0.15)
				)
				(justify left bottom)
				(hide yes)
			)
		)
		(property "Datasheet" ""
			(at 166.37 270.51 0)
			(effects
				(font
					(size 1.27 1.27)
					(thickness 0.15)
				)
				(justify left bottom)
				(hide yes)
			)
		)
		(property "Description" ""
			(at 161.29 262.89 0)
			(effects
				(font
					(size 1.27 1.27)
				)
				(hide yes)
			)
		)
		(property "MPN" ""
			(at 161.29 262.89 0)
			(effects
				(font
					(size 1.27 1.27)
					(thickness 0.15)
				)
				(justify left bottom)
				(hide yes)
			)
		)
		(property "Manufacturer" ""
			(at 161.29 262.89 0)
			(effects
				(font
					(size 1.27 1.27)
					(thickness 0.15)
				)
				(justify left bottom)
				(hide yes)
			)
		)
		(property "Author" "Antmicro"
			(at 176.53 247.65 0)
			(effects
				(font
					(size 1.27 1.27)
					(thickness 0.15)
				)
				(justify left bottom)
				(hide yes)
			)
		)
		(property "License" "Apache-2.0"
			(at 176.53 245.11 0)
			(effects
				(font
					(size 1.27 1.27)
					(thickness 0.15)
				)
				(justify left bottom)
				(hide yes)
			)
		)
		(pin "1"
		)
		(instances
			(project "cm4-baseboard"
				(path ""
					(reference "TP910")
					(unit 1)
				)
			)
			(project "usb"
				(path ""
					(reference "TP910")
					(unit 1)
				)
			)
		)
	)
	(symbol
		(lib_id "antmicroTransistorsFETsMOSFETsSingle:PJE138K")
		(at 318.77 240.03 0)
		(unit 1)
		(exclude_from_sim no)
		(in_bom yes)
		(on_board yes)
		(dnp no)
		(property "Reference" "Q905"
			(at 324.485 229.87 0)
			(effects
				(font
					(size 1.27 1.27)
				)
				(justify right)
			)
		)
		(property "Value" "PJE138K"
			(at 324.485 232.41 0)
			(effects
				(font
					(size 1.27 1.27)
				)
				(justify right)
			)
		)
		(property "Footprint" "antmicro-footprints:SOT-523"
			(at 323.85 234.95 0)
			(effects
				(font
					(size 1.524 1.524)
				)
				(justify left bottom)
				(hide yes)
			)
		)
		(property "Datasheet" "https://www.mouser.com/datasheet/2/1057/PJE138K-1876698.pdf"
			(at 323.85 232.41 0)
			(effects
				(font
					(size 1.524 1.524)
				)
				(justify left bottom)
				(hide yes)
			)
		)
		(property "Description" ""
			(at 318.77 240.03 0)
			(effects
				(font
					(size 1.27 1.27)
				)
				(hide yes)
			)
		)
		(property "MPN" "PJE138K_R1_00001"
			(at 335.28 229.87 0)
			(effects
				(font
					(size 1.524 1.524)
				)
				(justify left bottom)
				(hide yes)
			)
		)
		(property "Manufacturer" "PANJIT"
			(at 323.85 229.87 0)
			(effects
				(font
					(size 1.524 1.524)
				)
				(justify left bottom)
				(hide yes)
			)
		)
		(property "Author" "Antmicro"
			(at 341.63 261.62 0)
			(effects
				(font
					(size 1.27 1.27)
					(thickness 0.15)
				)
				(justify left bottom)
				(hide yes)
			)
		)
		(property "License" "Apache-2.0"
			(at 341.63 264.16 0)
			(effects
				(font
					(size 1.27 1.27)
					(thickness 0.15)
				)
				(justify left bottom)
				(hide yes)
			)
		)
		(pin "1"
		)
		(pin "2"
		)
		(pin "3"
		)
		(instances
			(project "cm4-baseboard"
				(path ""
					(reference "Q905")
					(unit 1)
				)
			)
		)
	)
	(symbol
		(lib_id "antmicropower:GND")
		(at 80.01 207.01 0)
		(unit 1)
		(exclude_from_sim no)
		(in_bom yes)
		(on_board yes)
		(dnp no)
		(fields_autoplaced yes)
		(property "Reference" "#PWR0905"
			(at 88.9 209.55 0)
			(effects
				(font
					(size 1.27 1.27)
					(thickness 0.15)
				)
				(justify left bottom)
				(hide yes)
			)
		)
		(property "Value" "GND"
			(at 77.9998 212.09 0)
			(effects
				(font
					(size 1.27 1.27)
					(thickness 0.15)
				)
				(justify left bottom)
			)
		)
		(property "Footprint" ""
			(at 88.9 214.63 0)
			(effects
				(font
					(size 1.27 1.27)
					(thickness 0.15)
				)
				(justify left bottom)
				(hide yes)
			)
		)
		(property "Datasheet" ""
			(at 88.9 219.71 0)
			(effects
				(font
					(size 1.27 1.27)
					(thickness 0.15)
				)
				(justify left bottom)
				(hide yes)
			)
		)
		(property "Description" ""
			(at 80.01 207.01 0)
			(effects
				(font
					(size 1.27 1.27)
				)
				(hide yes)
			)
		)
		(property "Author" "Antmicro"
			(at 88.9 214.63 0)
			(effects
				(font
					(size 1.27 1.27)
					(thickness 0.15)
				)
				(justify left bottom)
				(hide yes)
			)
		)
		(property "License" "Apache-2.0"
			(at 88.9 217.17 0)
			(effects
				(font
					(size 1.27 1.27)
					(thickness 0.15)
				)
				(justify left bottom)
				(hide yes)
			)
		)
		(pin "1"
		)
		(instances
			(project "cm4-baseboard"
				(path ""
					(reference "#PWR0905")
					(unit 1)
				)
			)
			(project "usb"
				(path ""
					(reference "#PWR0905")
					(unit 1)
				)
			)
		)
	)
	(symbol
		(lib_id "antmicropower:GND")
		(at 289.56 77.47 0)
		(unit 1)
		(exclude_from_sim no)
		(in_bom yes)
		(on_board yes)
		(dnp no)
		(property "Reference" "#PWR0943"
			(at 289.56 83.82 0)
			(effects
				(font
					(size 1.27 1.27)
				)
				(hide yes)
			)
		)
		(property "Value" "GND"
			(at 289.56 81.28 0)
			(effects
				(font
					(size 1.27 1.27)
				)
			)
		)
		(property "Footprint" ""
			(at 298.45 85.09 0)
			(effects
				(font
					(size 1.27 1.27)
					(thickness 0.15)
				)
				(justify left bottom)
				(hide yes)
			)
		)
		(property "Datasheet" ""
			(at 298.45 90.17 0)
			(effects
				(font
					(size 1.27 1.27)
					(thickness 0.15)
				)
				(justify left bottom)
				(hide yes)
			)
		)
		(property "Description" ""
			(at 289.56 77.47 0)
			(effects
				(font
					(size 1.27 1.27)
				)
				(hide yes)
			)
		)
		(property "Author" "Antmicro"
			(at 298.45 85.09 0)
			(effects
				(font
					(size 1.27 1.27)
					(thickness 0.15)
				)
				(justify left bottom)
				(hide yes)
			)
		)
		(property "License" "Apache-2.0"
			(at 298.45 87.63 0)
			(effects
				(font
					(size 1.27 1.27)
					(thickness 0.15)
				)
				(justify left bottom)
				(hide yes)
			)
		)
		(pin "1"
		)
		(instances
			(project "cm4-baseboard"
				(path ""
					(reference "#PWR0943")
					(unit 1)
				)
			)
			(project "usb"
				(path ""
					(reference "#PWR0943")
					(unit 1)
				)
			)
		)
	)
	(symbol
		(lib_id "antmicropower:GND")
		(at 266.7 45.72 0)
		(unit 1)
		(exclude_from_sim no)
		(in_bom yes)
		(on_board yes)
		(dnp no)
		(property "Reference" "#PWR0936"
			(at 266.7 52.07 0)
			(effects
				(font
					(size 1.27 1.27)
				)
				(hide yes)
			)
		)
		(property "Value" "GND"
			(at 266.7 49.53 0)
			(effects
				(font
					(size 1.27 1.27)
				)
			)
		)
		(property "Footprint" ""
			(at 275.59 53.34 0)
			(effects
				(font
					(size 1.27 1.27)
					(thickness 0.15)
				)
				(justify left bottom)
				(hide yes)
			)
		)
		(property "Datasheet" ""
			(at 275.59 58.42 0)
			(effects
				(font
					(size 1.27 1.27)
					(thickness 0.15)
				)
				(justify left bottom)
				(hide yes)
			)
		)
		(property "Description" ""
			(at 266.7 45.72 0)
			(effects
				(font
					(size 1.27 1.27)
				)
				(hide yes)
			)
		)
		(property "Author" "Antmicro"
			(at 275.59 53.34 0)
			(effects
				(font
					(size 1.27 1.27)
					(thickness 0.15)
				)
				(justify left bottom)
				(hide yes)
			)
		)
		(property "License" "Apache-2.0"
			(at 275.59 55.88 0)
			(effects
				(font
					(size 1.27 1.27)
					(thickness 0.15)
				)
				(justify left bottom)
				(hide yes)
			)
		)
		(pin "1"
		)
		(instances
			(project "cm4-baseboard"
				(path ""
					(reference "#PWR0936")
					(unit 1)
				)
			)
			(project "usb"
				(path ""
					(reference "#PWR0936")
					(unit 1)
				)
			)
		)
	)
	(symbol
		(lib_id "antmicroCapacitorsmisc:C_22u_25V_0805")
		(at 231.14 60.96 270)
		(unit 1)
		(exclude_from_sim no)
		(in_bom yes)
		(on_board yes)
		(dnp no)
		(property "Reference" "C907"
			(at 228.6 60.9663 90)
			(effects
				(font
					(size 1.27 1.27)
				)
				(justify right)
			)
		)
		(property "Value" "C_22u_25V_0805"
			(at 227.33 60.96 0)
			(effects
				(font
					(size 1.27 1.27)
				)
				(justify left bottom)
				(hide yes)
			)
		)
		(property "Footprint" "antmicro-footprints:C_0805_2012Metric"
			(at 236.22 66.04 0)
			(effects
				(font
					(size 1.524 1.524)
				)
				(justify left bottom)
				(hide yes)
			)
		)
		(property "Datasheet" "https://product.samsungsem.com/mlcc/CL21A226MAYNNN.do"
			(at 231.14 60.96 0)
			(effects
				(font
					(size 1.27 1.27)
				)
				(justify left bottom)
				(hide yes)
			)
		)
		(property "Description" ""
			(at 231.14 60.96 0)
			(effects
				(font
					(size 1.27 1.27)
				)
				(hide yes)
			)
		)
		(property "Manufacturer" "Samsung Electro-Mechanics"
			(at 241.3 66.04 0)
			(effects
				(font
					(size 1.524 1.524)
				)
				(justify left bottom)
				(hide yes)
			)
		)
		(property "MPN" "CL21A226MAYNNNE"
			(at 238.76 66.04 0)
			(effects
				(font
					(size 1.524 1.524)
				)
				(justify left bottom)
				(hide yes)
			)
		)
		(property "Val" "22u"
			(at 228.6 63.5063 90)
			(effects
				(font
					(size 1.27 1.27)
				)
				(justify right)
			)
		)
		(property "License" "Apache-2.0"
			(at 208.28 81.28 0)
			(effects
				(font
					(size 1.27 1.27)
					(thickness 0.15)
				)
				(justify left bottom)
				(hide yes)
			)
		)
		(property "Author" "Antmicro"
			(at 205.74 81.28 0)
			(effects
				(font
					(size 1.27 1.27)
					(thickness 0.15)
				)
				(justify left bottom)
				(hide yes)
			)
		)
		(property "Voltage" "25V"
			(at 228.6 66.0463 90)
			(effects
				(font
					(size 1.27 1.27)
				)
				(justify right)
			)
		)
		(property "Dielectric" "X5R"
			(at 200.66 81.28 0)
			(effects
				(font
					(size 1.27 1.27)
				)
				(justify left bottom)
				(hide yes)
			)
		)
		(property "Public" "False"
			(at 198.12 81.28 0)
			(effects
				(font
					(size 1.27 1.27)
				)
				(justify left bottom)
				(hide yes)
			)
		)
		(pin "1"
		)
		(pin "2"
		)
		(instances
			(project "cm4-baseboard"
				(path ""
					(reference "C907")
					(unit 1)
				)
			)
			(project "usb"
				(path ""
					(reference "C907")
					(unit 1)
				)
			)
		)
	)
	(symbol
		(lib_id "antmicroCapacitors0402:C_4u7_0402")
		(at 300.99 149.86 270)
		(unit 1)
		(exclude_from_sim no)
		(in_bom yes)
		(on_board yes)
		(dnp no)
		(property "Reference" "C925"
			(at 301.625 150.495 90)
			(effects
				(font
					(size 1.27 1.27)
				)
				(justify left)
			)
		)
		(property "Value" "C_4u7_0402"
			(at 297.18 149.86 0)
			(effects
				(font
					(size 1.27 1.27)
					(thickness 0.15)
				)
				(justify left bottom)
				(hide yes)
			)
		)
		(property "Footprint" "antmicro-footprints:C_0402_1005Metric"
			(at 306.07 154.94 0)
			(effects
				(font
					(size 1.27 1.27)
					(thickness 0.15)
				)
				(justify left bottom)
				(hide yes)
			)
		)
		(property "Datasheet" "https://www.murata.com/products/productdetail?partno=GRM155R61A475MEAA%23"
			(at 300.99 149.86 0)
			(effects
				(font
					(size 1.27 1.27)
					(thickness 0.15)
				)
				(justify left bottom)
				(hide yes)
			)
		)
		(property "Description" ""
			(at 300.99 149.86 0)
			(effects
				(font
					(size 1.27 1.27)
				)
				(hide yes)
			)
		)
		(property "Manufacturer" "Murata"
			(at 311.15 154.94 0)
			(effects
				(font
					(size 1.27 1.27)
					(thickness 0.15)
				)
				(justify left bottom)
				(hide yes)
			)
		)
		(property "MPN" "GRM155R61A475MEAAD"
			(at 308.61 154.94 0)
			(effects
				(font
					(size 1.27 1.27)
					(thickness 0.15)
				)
				(justify left bottom)
				(hide yes)
			)
		)
		(property "Val" "4u7"
			(at 301.625 154.305 90)
			(effects
				(font
					(size 1.27 1.27)
					(thickness 0.15)
				)
				(justify left)
			)
		)
		(property "License" "Apache-2.0"
			(at 278.13 170.18 0)
			(effects
				(font
					(size 1.27 1.27)
					(thickness 0.15)
				)
				(justify left bottom)
				(hide yes)
			)
		)
		(property "Author" "Antmicro"
			(at 275.59 170.18 0)
			(effects
				(font
					(size 1.27 1.27)
					(thickness 0.15)
				)
				(justify left bottom)
				(hide yes)
			)
		)
		(property "Voltage" ""
			(at 273.05 170.18 0)
			(effects
				(font
					(size 1.27 1.27)
				)
				(justify left bottom)
				(hide yes)
			)
		)
		(property "Dielectric" ""
			(at 270.51 170.18 0)
			(effects
				(font
					(size 1.27 1.27)
				)
				(justify left bottom)
				(hide yes)
			)
		)
		(pin "1"
		)
		(pin "2"
		)
		(instances
			(project "cm4-baseboard"
				(path ""
					(reference "C925")
					(unit 1)
				)
			)
			(project "usb"
				(path ""
					(reference "C925")
					(unit 1)
				)
			)
		)
	)
	(symbol
		(lib_id "antmicropower:GND")
		(at 372.11 170.18 0)
		(unit 1)
		(exclude_from_sim no)
		(in_bom yes)
		(on_board yes)
		(dnp no)
		(fields_autoplaced yes)
		(property "Reference" "#PWR023"
			(at 381 172.72 0)
			(effects
				(font
					(size 1.27 1.27)
					(thickness 0.15)
				)
				(justify left bottom)
				(hide yes)
			)
		)
		(property "Value" "GND"
			(at 372.11 174.625 0)
			(effects
				(font
					(size 1.27 1.27)
					(thickness 0.15)
				)
			)
		)
		(property "Footprint" ""
			(at 381 177.8 0)
			(effects
				(font
					(size 1.27 1.27)
					(thickness 0.15)
				)
				(justify left bottom)
				(hide yes)
			)
		)
		(property "Datasheet" ""
			(at 381 182.88 0)
			(effects
				(font
					(size 1.27 1.27)
					(thickness 0.15)
				)
				(justify left bottom)
				(hide yes)
			)
		)
		(property "Description" ""
			(at 372.11 170.18 0)
			(effects
				(font
					(size 1.27 1.27)
				)
				(hide yes)
			)
		)
		(property "Author" "Antmicro"
			(at 381 177.8 0)
			(effects
				(font
					(size 1.27 1.27)
					(thickness 0.15)
				)
				(justify left bottom)
				(hide yes)
			)
		)
		(property "License" "Apache-2.0"
			(at 381 180.34 0)
			(effects
				(font
					(size 1.27 1.27)
					(thickness 0.15)
				)
				(justify left bottom)
				(hide yes)
			)
		)
		(pin "1"
		)
		(instances
			(project "cm4-baseboard"
				(path ""
					(reference "#PWR023")
					(unit 1)
				)
			)
		)
	)
	(symbol
		(lib_id "antmicroResistors0402:R_0R_0402")
		(at 250.19 54.61 0)
		(unit 1)
		(exclude_from_sim no)
		(in_bom yes)
		(on_board yes)
		(dnp no)
		(property "Reference" "R919"
			(at 252.73 49.53 0)
			(effects
				(font
					(size 1.27 1.27)
				)
			)
		)
		(property "Value" "R_0R_0402"
			(at 250.19 58.42 0)
			(effects
				(font
					(size 1.27 1.27)
				)
				(justify left bottom)
				(hide yes)
			)
		)
		(property "Footprint" "antmicro-footprints:R_0402_1005Metric"
			(at 255.27 49.53 0)
			(effects
				(font
					(size 1.524 1.524)
				)
				(justify left bottom)
				(hide yes)
			)
		)
		(property "Datasheet" "https://industrial.panasonic.com/cdbs/www-data/pdf/RDA0000/AOA0000C301.pdf"
			(at 250.19 54.61 0)
			(effects
				(font
					(size 1.27 1.27)
				)
				(justify left bottom)
				(hide yes)
			)
		)
		(property "Description" ""
			(at 250.19 54.61 0)
			(effects
				(font
					(size 1.27 1.27)
				)
				(hide yes)
			)
		)
		(property "Manufacturer" "Panasonic"
			(at 255.27 44.45 0)
			(effects
				(font
					(size 1.524 1.524)
				)
				(justify left bottom)
				(hide yes)
			)
		)
		(property "MPN" "ERJ2GE0R00X"
			(at 255.27 46.99 0)
			(effects
				(font
					(size 1.524 1.524)
				)
				(justify left bottom)
				(hide yes)
			)
		)
		(property "Val" "0R"
			(at 252.73 52.07 0)
			(effects
				(font
					(size 1.27 1.27)
				)
			)
		)
		(property "License" "Apache-2.0"
			(at 270.51 80.01 0)
			(effects
				(font
					(size 1.27 1.27)
					(thickness 0.15)
				)
				(justify left bottom)
				(hide yes)
			)
		)
		(property "Author" "Antmicro"
			(at 270.51 82.55 0)
			(effects
				(font
					(size 1.27 1.27)
					(thickness 0.15)
				)
				(justify left bottom)
				(hide yes)
			)
		)
		(property "Tolerance" "~"
			(at 270.51 64.77 0)
			(effects
				(font
					(size 1.27 1.27)
				)
				(justify left bottom)
				(hide yes)
			)
		)
		(property "Current" "1A"
			(at 252.73 52.705 0)
			(effects
				(font
					(size 1.27 1.27)
					(thickness 0.15)
				)
				(hide yes)
			)
		)
		(pin "1"
		)
		(pin "2"
		)
		(instances
			(project "cm4-baseboard"
				(path ""
					(reference "R919")
					(unit 1)
				)
			)
			(project "usb"
				(path ""
					(reference "R919")
					(unit 1)
				)
			)
		)
	)
	(symbol
		(lib_id "antmicroTVSDiodes:SMF4L15A")
		(at 71.12 59.69 90)
		(mirror x)
		(unit 1)
		(exclude_from_sim no)
		(in_bom yes)
		(on_board yes)
		(dnp no)
		(property "Reference" "D904"
			(at 69.215 60.96 90)
			(effects
				(font
					(size 1.27 1.27)
					(thickness 0.15)
				)
				(justify left)
			)
		)
		(property "Value" "SMF4L15A"
			(at 68.58 63.5 90)
			(effects
				(font
					(size 1.27 1.27)
					(thickness 0.15)
				)
				(justify left)
				(hide yes)
			)
		)
		(property "Footprint" "antmicro-footprints:SOD-123FL"
			(at 81.28 86.36 0)
			(effects
				(font
					(size 1.27 1.27)
					(thickness 0.15)
				)
				(justify left bottom)
				(hide yes)
			)
		)
		(property "Datasheet" "https://www.littelfuse.com/media?resourcetype=datasheets&itemid=d2ba8fab-1de3-4176-8530-f36ecb0b8799&filename=smf4l"
			(at 83.82 86.36 0)
			(effects
				(font
					(size 1.27 1.27)
					(thickness 0.15)
				)
				(justify left bottom)
				(hide yes)
			)
		)
		(property "Description" ""
			(at 71.12 59.69 0)
			(effects
				(font
					(size 1.27 1.27)
				)
				(hide yes)
			)
		)
		(property "MPN" "SMF4L15A"
			(at 69.215 63.5 90)
			(effects
				(font
					(size 1.27 1.27)
					(thickness 0.15)
				)
				(justify left)
			)
		)
		(property "Manufacturer" "Littelfuse"
			(at 88.9 86.36 0)
			(effects
				(font
					(size 1.27 1.27)
					(thickness 0.15)
				)
				(justify left bottom)
				(hide yes)
			)
		)
		(property "Author" "Antmicro"
			(at 91.44 86.36 0)
			(effects
				(font
					(size 1.27 1.27)
					(thickness 0.15)
				)
				(justify left bottom)
				(hide yes)
			)
		)
		(property "License" "Apache-2.0"
			(at 93.98 86.36 0)
			(effects
				(font
					(size 1.27 1.27)
					(thickness 0.15)
				)
				(justify left bottom)
				(hide yes)
			)
		)
		(pin "1"
		)
		(pin "2"
		)
		(instances
			(project "cm4-baseboard"
				(path ""
					(reference "D904")
					(unit 1)
				)
			)
			(project "usb"
				(path ""
					(reference "D904")
					(unit 1)
				)
			)
		)
	)
	(symbol
		(lib_id "antmicroTVSDiodes:PESD5Z5_0F")
		(at 80.01 199.39 90)
		(mirror x)
		(unit 1)
		(exclude_from_sim no)
		(in_bom yes)
		(on_board yes)
		(dnp no)
		(property "Reference" "D903"
			(at 77.47 200.66 90)
			(effects
				(font
					(size 1.27 1.27)
					(thickness 0.15)
				)
				(justify left)
			)
		)
		(property "Value" "PESD5Z5_0F"
			(at 77.47 202.2475 90)
			(effects
				(font
					(size 1.27 1.27)
					(thickness 0.15)
				)
				(justify left)
				(hide yes)
			)
		)
		(property "Footprint" "antmicro-footprints:SOD-523"
			(at 85.09 214.63 0)
			(effects
				(font
					(size 1.27 1.27)
					(thickness 0.15)
				)
				(justify left bottom)
				(hide yes)
			)
		)
		(property "Datasheet" "https://assets.nexperia.com/documents/data-sheet/PESD5Z5_0.pdf"
			(at 87.63 214.63 0)
			(effects
				(font
					(size 1.27 1.27)
					(thickness 0.15)
				)
				(justify left bottom)
				(hide yes)
			)
		)
		(property "Description" ""
			(at 80.01 199.39 0)
			(effects
				(font
					(size 1.27 1.27)
				)
				(hide yes)
			)
		)
		(property "Manufacturer" "Nexperia"
			(at 90.17 214.63 0)
			(effects
				(font
					(size 1.27 1.27)
					(thickness 0.15)
				)
				(justify left bottom)
				(hide yes)
			)
		)
		(property "MPN" "PESD5Z5.0F"
			(at 77.47 203.2 90)
			(effects
				(font
					(size 1.27 1.27)
					(thickness 0.15)
				)
				(justify left)
			)
		)
		(property "Author" "Antmicro"
			(at 95.25 214.63 0)
			(effects
				(font
					(size 1.27 1.27)
					(thickness 0.15)
				)
				(justify left bottom)
				(hide yes)
			)
		)
		(property "License" "Apache-2.0"
			(at 97.79 214.63 0)
			(effects
				(font
					(size 1.27 1.27)
					(thickness 0.15)
				)
				(justify left bottom)
				(hide yes)
			)
		)
		(pin "2"
		)
		(pin "1"
		)
		(instances
			(project "cm4-baseboard"
				(path ""
					(reference "D903")
					(unit 1)
				)
			)
			(project "usb"
				(path ""
					(reference "D903")
					(unit 1)
				)
			)
		)
	)
	(symbol
		(lib_id "antmicroTestPoints:TP_0.75mm_SMD")
		(at 161.29 252.73 0)
		(mirror x)
		(unit 1)
		(exclude_from_sim no)
		(in_bom no)
		(on_board yes)
		(dnp no)
		(property "Reference" "TP901"
			(at 162.56 251.46 0)
			(effects
				(font
					(size 1.27 1.27)
				)
				(justify left top)
			)
		)
		(property "Value" "TP_0.75mm_SMD"
			(at 161.29 250.19 0)
			(effects
				(font
					(size 1.27 1.27)
					(thickness 0.15)
				)
				(justify left bottom)
				(hide yes)
			)
		)
		(property "Footprint" "antmicro-footprints:TP_SMD_0.75mm"
			(at 166.37 257.81 0)
			(effects
				(font
					(size 1.27 1.27)
					(thickness 0.15)
				)
				(justify left bottom)
				(hide yes)
			)
		)
		(property "Datasheet" ""
			(at 166.37 260.35 0)
			(effects
				(font
					(size 1.27 1.27)
					(thickness 0.15)
				)
				(justify left bottom)
				(hide yes)
			)
		)
		(property "Description" ""
			(at 161.29 252.73 0)
			(effects
				(font
					(size 1.27 1.27)
				)
				(hide yes)
			)
		)
		(property "MPN" ""
			(at 161.29 252.73 0)
			(effects
				(font
					(size 1.27 1.27)
					(thickness 0.15)
				)
				(justify left bottom)
				(hide yes)
			)
		)
		(property "Manufacturer" ""
			(at 161.29 252.73 0)
			(effects
				(font
					(size 1.27 1.27)
					(thickness 0.15)
				)
				(justify left bottom)
				(hide yes)
			)
		)
		(property "Author" "Antmicro"
			(at 176.53 237.49 0)
			(effects
				(font
					(size 1.27 1.27)
					(thickness 0.15)
				)
				(justify left bottom)
				(hide yes)
			)
		)
		(property "License" "Apache-2.0"
			(at 176.53 234.95 0)
			(effects
				(font
					(size 1.27 1.27)
					(thickness 0.15)
				)
				(justify left bottom)
				(hide yes)
			)
		)
		(pin "1"
		)
		(instances
			(project "cm4-baseboard"
				(path ""
					(reference "TP901")
					(unit 1)
				)
			)
			(project "usb"
				(path ""
					(reference "TP901")
					(unit 1)
				)
			)
		)
	)
	(symbol
		(lib_id "antmicroCapacitorsmisc:C_22u_25V_0805")
		(at 86.36 59.69 90)
		(mirror x)
		(unit 1)
		(exclude_from_sim no)
		(in_bom yes)
		(on_board yes)
		(dnp no)
		(property "Reference" "C932"
			(at 87.63 60.96 90)
			(effects
				(font
					(size 1.27 1.27)
				)
				(justify right)
			)
		)
		(property "Value" "C_22u_25V_0805"
			(at 90.17 59.69 0)
			(effects
				(font
					(size 1.27 1.27)
				)
				(justify left bottom)
				(hide yes)
			)
		)
		(property "Footprint" "antmicro-footprints:C_0805_2012Metric"
			(at 81.28 64.77 0)
			(effects
				(font
					(size 1.524 1.524)
				)
				(justify left bottom)
				(hide yes)
			)
		)
		(property "Datasheet" "https://product.samsungsem.com/mlcc/CL21A226MAYNNN.do"
			(at 86.36 59.69 0)
			(effects
				(font
					(size 1.27 1.27)
				)
				(justify left bottom)
				(hide yes)
			)
		)
		(property "Description" ""
			(at 86.36 59.69 0)
			(effects
				(font
					(size 1.27 1.27)
				)
				(hide yes)
			)
		)
		(property "Manufacturer" "Samsung Electro-Mechanics"
			(at 76.2 64.77 0)
			(effects
				(font
					(size 1.524 1.524)
				)
				(justify left bottom)
				(hide yes)
			)
		)
		(property "MPN" "CL21A226MAYNNNE"
			(at 78.74 64.77 0)
			(effects
				(font
					(size 1.524 1.524)
				)
				(justify left bottom)
				(hide yes)
			)
		)
		(property "Val" "22u"
			(at 87.63 63.5 90)
			(effects
				(font
					(size 1.27 1.27)
				)
				(justify right)
			)
		)
		(property "License" "Apache-2.0"
			(at 109.22 80.01 0)
			(effects
				(font
					(size 1.27 1.27)
					(thickness 0.15)
				)
				(justify left bottom)
				(hide yes)
			)
		)
		(property "Author" "Antmicro"
			(at 111.76 80.01 0)
			(effects
				(font
					(size 1.27 1.27)
					(thickness 0.15)
				)
				(justify left bottom)
				(hide yes)
			)
		)
		(property "Voltage" "25V"
			(at 87.63 66.04 90)
			(effects
				(font
					(size 1.27 1.27)
				)
				(justify right)
			)
		)
		(property "Dielectric" "X5R"
			(at 116.84 80.01 0)
			(effects
				(font
					(size 1.27 1.27)
				)
				(justify left bottom)
				(hide yes)
			)
		)
		(property "Public" "False"
			(at 119.38 80.01 0)
			(effects
				(font
					(size 1.27 1.27)
				)
				(justify left bottom)
				(hide yes)
			)
		)
		(pin "1"
		)
		(pin "2"
		)
		(instances
			(project "cm4-baseboard"
				(path ""
					(reference "C932")
					(unit 1)
				)
			)
			(project "usb"
				(path ""
					(reference "C932")
					(unit 1)
				)
			)
		)
	)
	(symbol
		(lib_id "antmicroResistors0402:R_910k_0402")
		(at 110.49 243.84 270)
		(unit 1)
		(exclude_from_sim no)
		(in_bom yes)
		(on_board yes)
		(dnp no)
		(property "Reference" "R903"
			(at 113.03 245.11 90)
			(effects
				(font
					(size 1.27 1.27)
					(thickness 0.15)
				)
				(justify left)
			)
		)
		(property "Value" "R_910k_0402"
			(at 97.79 264.16 0)
			(effects
				(font
					(size 1.27 1.27)
					(thickness 0.15)
				)
				(justify left bottom)
				(hide yes)
			)
		)
		(property "Footprint" "antmicro-footprints:R_0402_1005Metric"
			(at 95.25 264.16 0)
			(effects
				(font
					(size 1.27 1.27)
					(thickness 0.15)
				)
				(justify left bottom)
				(hide yes)
			)
		)
		(property "Datasheet" "https://www.bourns.com/docs/product-datasheets/cr.pdf"
			(at 92.71 264.16 0)
			(effects
				(font
					(size 1.27 1.27)
					(thickness 0.15)
				)
				(justify left bottom)
				(hide yes)
			)
		)
		(property "Description" ""
			(at 110.49 243.84 0)
			(effects
				(font
					(size 1.27 1.27)
				)
				(hide yes)
			)
		)
		(property "MPN" "CR0402-FX-9103GLF"
			(at 90.17 264.16 0)
			(effects
				(font
					(size 1.27 1.27)
					(thickness 0.15)
				)
				(justify left bottom)
				(hide yes)
			)
		)
		(property "Manufacturer" "Bourns"
			(at 87.63 264.16 0)
			(effects
				(font
					(size 1.27 1.27)
					(thickness 0.15)
				)
				(justify left bottom)
				(hide yes)
			)
		)
		(property "License" "Apache-2.0"
			(at 85.09 264.16 0)
			(effects
				(font
					(size 1.27 1.27)
					(thickness 0.15)
				)
				(justify left bottom)
				(hide yes)
			)
		)
		(property "Author" "Antmicro"
			(at 82.55 264.16 0)
			(effects
				(font
					(size 1.27 1.27)
					(thickness 0.15)
				)
				(justify left bottom)
				(hide yes)
			)
		)
		(property "Val" "910k"
			(at 113.03 247.65 90)
			(effects
				(font
					(size 1.27 1.27)
					(thickness 0.15)
				)
				(justify left)
			)
		)
		(property "Tolerance" "1%"
			(at 100.33 264.16 0)
			(effects
				(font
					(size 1.27 1.27)
				)
				(justify left bottom)
				(hide yes)
			)
		)
		(pin "1"
		)
		(pin "2"
		)
		(instances
			(project "cm4-baseboard"
				(path ""
					(reference "R903")
					(unit 1)
				)
			)
			(project "usb"
				(path ""
					(reference "R903")
					(unit 1)
				)
			)
		)
	)
	(symbol
		(lib_id "antmicropower:GND")
		(at 231.14 72.39 0)
		(unit 1)
		(exclude_from_sim no)
		(in_bom yes)
		(on_board yes)
		(dnp no)
		(fields_autoplaced yes)
		(property "Reference" "#PWR0923"
			(at 240.03 74.93 0)
			(effects
				(font
					(size 1.27 1.27)
					(thickness 0.15)
				)
				(justify left bottom)
				(hide yes)
			)
		)
		(property "Value" "GND"
			(at 229.1298 77.47 0)
			(effects
				(font
					(size 1.27 1.27)
					(thickness 0.15)
				)
				(justify left bottom)
			)
		)
		(property "Footprint" ""
			(at 240.03 80.01 0)
			(effects
				(font
					(size 1.27 1.27)
					(thickness 0.15)
				)
				(justify left bottom)
				(hide yes)
			)
		)
		(property "Datasheet" ""
			(at 240.03 85.09 0)
			(effects
				(font
					(size 1.27 1.27)
					(thickness 0.15)
				)
				(justify left bottom)
				(hide yes)
			)
		)
		(property "Description" ""
			(at 231.14 72.39 0)
			(effects
				(font
					(size 1.27 1.27)
				)
				(hide yes)
			)
		)
		(property "Author" "Antmicro"
			(at 240.03 80.01 0)
			(effects
				(font
					(size 1.27 1.27)
					(thickness 0.15)
				)
				(justify left bottom)
				(hide yes)
			)
		)
		(property "License" "Apache-2.0"
			(at 240.03 82.55 0)
			(effects
				(font
					(size 1.27 1.27)
					(thickness 0.15)
				)
				(justify left bottom)
				(hide yes)
			)
		)
		(pin "1"
		)
		(instances
			(project "cm4-baseboard"
				(path ""
					(reference "#PWR0923")
					(unit 1)
				)
			)
			(project "usb"
				(path ""
					(reference "#PWR0923")
					(unit 1)
				)
			)
		)
	)
	(symbol
		(lib_id "antmicroCapacitors0402:C_100n_0402")
		(at 278.13 149.86 270)
		(unit 1)
		(exclude_from_sim no)
		(in_bom yes)
		(on_board yes)
		(dnp no)
		(property "Reference" "C916"
			(at 278.765 150.495 90)
			(effects
				(font
					(size 1.27 1.27)
				)
				(justify left)
			)
		)
		(property "Value" "C_100n_0402"
			(at 274.32 149.86 0)
			(effects
				(font
					(size 1.27 1.27)
					(thickness 0.15)
				)
				(justify left bottom)
				(hide yes)
			)
		)
		(property "Footprint" "antmicro-footprints:C_0402_1005Metric"
			(at 283.21 154.94 0)
			(effects
				(font
					(size 1.27 1.27)
					(thickness 0.15)
				)
				(justify left bottom)
				(hide yes)
			)
		)
		(property "Datasheet" "https://www.murata.com/products/productdetail?partno=GRM155R61H104KE14%23"
			(at 278.13 149.86 0)
			(effects
				(font
					(size 1.27 1.27)
					(thickness 0.15)
				)
				(justify left bottom)
				(hide yes)
			)
		)
		(property "Description" ""
			(at 278.13 149.86 0)
			(effects
				(font
					(size 1.27 1.27)
				)
				(hide yes)
			)
		)
		(property "Manufacturer" "Murata"
			(at 288.29 154.94 0)
			(effects
				(font
					(size 1.27 1.27)
					(thickness 0.15)
				)
				(justify left bottom)
				(hide yes)
			)
		)
		(property "MPN" "GRM155R61H104KE14D"
			(at 285.75 154.94 0)
			(effects
				(font
					(size 1.27 1.27)
					(thickness 0.15)
				)
				(justify left bottom)
				(hide yes)
			)
		)
		(property "Val" "100n"
			(at 278.765 154.305 90)
			(effects
				(font
					(size 1.27 1.27)
					(thickness 0.15)
				)
				(justify left)
			)
		)
		(property "License" "Apache-2.0"
			(at 255.27 170.18 0)
			(effects
				(font
					(size 1.27 1.27)
					(thickness 0.15)
				)
				(justify left bottom)
				(hide yes)
			)
		)
		(property "Author" "Antmicro"
			(at 252.73 170.18 0)
			(effects
				(font
					(size 1.27 1.27)
					(thickness 0.15)
				)
				(justify left bottom)
				(hide yes)
			)
		)
		(property "Voltage" "50V"
			(at 250.19 170.18 0)
			(effects
				(font
					(size 1.27 1.27)
				)
				(justify left bottom)
				(hide yes)
			)
		)
		(property "Dielectric" "X5R"
			(at 247.65 170.18 0)
			(effects
				(font
					(size 1.27 1.27)
				)
				(justify left bottom)
				(hide yes)
			)
		)
		(pin "1"
		)
		(pin "2"
		)
		(instances
			(project "cm4-baseboard"
				(path ""
					(reference "C916")
					(unit 1)
				)
			)
			(project "usb"
				(path ""
					(reference "C916")
					(unit 1)
				)
			)
		)
	)
	(symbol
		(lib_id "antmicropower:PWR_FLAG")
		(at 295.91 35.56 0)
		(unit 1)
		(exclude_from_sim no)
		(in_bom yes)
		(on_board yes)
		(dnp no)
		(property "Reference" "#FLG013"
			(at 295.91 33.655 0)
			(effects
				(font
					(size 1.27 1.27)
				)
				(hide yes)
			)
		)
		(property "Value" "PWR_FLAG"
			(at 295.91 31.75 0)
			(effects
				(font
					(size 1.27 1.27)
				)
			)
		)
		(property "Footprint" ""
			(at 295.91 35.56 0)
			(effects
				(font
					(size 1.27 1.27)
				)
				(hide yes)
			)
		)
		(property "Datasheet" ""
			(at 295.91 35.56 0)
			(effects
				(font
					(size 1.27 1.27)
				)
				(hide yes)
			)
		)
		(property "Description" ""
			(at 295.91 35.56 0)
			(effects
				(font
					(size 1.27 1.27)
				)
				(hide yes)
			)
		)
		(pin "1"
		)
		(instances
			(project "cm4-baseboard"
				(path ""
					(reference "#FLG013")
					(unit 1)
				)
			)
		)
	)
	(symbol
		(lib_id "antmicropower:+3V3")
		(at 384.81 162.56 0)
		(unit 1)
		(exclude_from_sim no)
		(in_bom yes)
		(on_board yes)
		(dnp no)
		(fields_autoplaced yes)
		(property "Reference" "#PWR024"
			(at 400.05 165.1 0)
			(effects
				(font
					(size 1.27 1.27)
					(thickness 0.15)
				)
				(justify left bottom)
				(hide yes)
			)
		)
		(property "Value" "+3V3"
			(at 384.175 158.75 0)
			(effects
				(font
					(size 1.27 1.27)
					(thickness 0.15)
				)
			)
		)
		(property "Footprint" ""
			(at 400.05 170.18 0)
			(effects
				(font
					(size 1.27 1.27)
					(thickness 0.15)
				)
				(justify left bottom)
				(hide yes)
			)
		)
		(property "Datasheet" ""
			(at 400.05 172.72 0)
			(effects
				(font
					(size 1.27 1.27)
					(thickness 0.15)
				)
				(justify left bottom)
				(hide yes)
			)
		)
		(property "Description" ""
			(at 384.81 162.56 0)
			(effects
				(font
					(size 1.27 1.27)
				)
				(hide yes)
			)
		)
		(property "Author" "Antmicro"
			(at 400.05 170.18 0)
			(effects
				(font
					(size 1.27 1.27)
					(thickness 0.15)
				)
				(justify left bottom)
				(hide yes)
			)
		)
		(property "License" "Apache-2.0"
			(at 400.05 172.72 0)
			(effects
				(font
					(size 1.27 1.27)
					(thickness 0.15)
				)
				(justify left bottom)
				(hide yes)
			)
		)
		(pin "1"
		)
		(instances
			(project "cm4-baseboard"
				(path ""
					(reference "#PWR024")
					(unit 1)
				)
			)
		)
	)
	(symbol
		(lib_id "antmicroTestPoints:TP_0.75mm_SMD")
		(at 243.84 50.8 90)
		(unit 1)
		(exclude_from_sim no)
		(in_bom no)
		(on_board yes)
		(dnp no)
		(property "Reference" "TP903"
			(at 240.665 45.72 90)
			(effects
				(font
					(size 1.27 1.27)
				)
				(justify right)
			)
		)
		(property "Value" "TP_0.75mm_SMD"
			(at 246.38 50.8 0)
			(effects
				(font
					(size 1.27 1.27)
				)
				(justify left bottom)
				(hide yes)
			)
		)
		(property "Footprint" "antmicro-footprints:TP_SMD_0.75mm"
			(at 238.76 45.72 0)
			(effects
				(font
					(size 1.524 1.524)
				)
				(justify left bottom)
				(hide yes)
			)
		)
		(property "Datasheet" ""
			(at 236.22 45.72 0)
			(effects
				(font
					(size 1.524 1.524)
				)
				(justify left bottom)
				(hide yes)
			)
		)
		(property "Description" ""
			(at 243.84 50.8 0)
			(effects
				(font
					(size 1.27 1.27)
				)
				(hide yes)
			)
		)
		(property "MPN" ""
			(at 243.84 50.8 0)
			(effects
				(font
					(size 1.27 1.27)
				)
				(hide yes)
			)
		)
		(property "Manufacturer" ""
			(at 243.84 50.8 0)
			(effects
				(font
					(size 1.27 1.27)
				)
				(hide yes)
			)
		)
		(property "Author" "Antmicro"
			(at 259.08 35.56 0)
			(effects
				(font
					(size 1.27 1.27)
					(thickness 0.15)
				)
				(justify left bottom)
				(hide yes)
			)
		)
		(property "License" "Apache-2.0"
			(at 261.62 35.56 0)
			(effects
				(font
					(size 1.27 1.27)
					(thickness 0.15)
				)
				(justify left bottom)
				(hide yes)
			)
		)
		(pin "1"
		)
		(instances
			(project "cm4-baseboard"
				(path ""
					(reference "TP903")
					(unit 1)
				)
			)
			(project "usb"
				(path ""
					(reference "TP903")
					(unit 1)
				)
			)
		)
	)
	(symbol
		(lib_id "antmicroCapacitors0402:C_100n_0402")
		(at 289.56 39.37 270)
		(unit 1)
		(exclude_from_sim no)
		(in_bom yes)
		(on_board yes)
		(dnp no)
		(property "Reference" "C922"
			(at 290.195 40.0177 90)
			(effects
				(font
					(size 1.27 1.27)
				)
				(justify left)
			)
		)
		(property "Value" "C_100n_0402"
			(at 285.75 39.37 0)
			(effects
				(font
					(size 1.27 1.27)
					(thickness 0.15)
				)
				(justify left bottom)
				(hide yes)
			)
		)
		(property "Footprint" "antmicro-footprints:C_0402_1005Metric"
			(at 294.64 44.45 0)
			(effects
				(font
					(size 1.27 1.27)
					(thickness 0.15)
				)
				(justify left bottom)
				(hide yes)
			)
		)
		(property "Datasheet" "https://www.murata.com/products/productdetail?partno=GRM155R61H104KE14%23"
			(at 289.56 39.37 0)
			(effects
				(font
					(size 1.27 1.27)
					(thickness 0.15)
				)
				(justify left bottom)
				(hide yes)
			)
		)
		(property "Description" ""
			(at 289.56 39.37 0)
			(effects
				(font
					(size 1.27 1.27)
				)
				(hide yes)
			)
		)
		(property "Manufacturer" "Murata"
			(at 299.72 44.45 0)
			(effects
				(font
					(size 1.27 1.27)
					(thickness 0.15)
				)
				(justify left bottom)
				(hide yes)
			)
		)
		(property "MPN" "GRM155R61H104KE14D"
			(at 297.18 44.45 0)
			(effects
				(font
					(size 1.27 1.27)
					(thickness 0.15)
				)
				(justify left bottom)
				(hide yes)
			)
		)
		(property "Val" "100n"
			(at 290.195 43.8277 90)
			(effects
				(font
					(size 1.27 1.27)
					(thickness 0.15)
				)
				(justify left)
			)
		)
		(property "License" "Apache-2.0"
			(at 266.7 59.69 0)
			(effects
				(font
					(size 1.27 1.27)
					(thickness 0.15)
				)
				(justify left bottom)
				(hide yes)
			)
		)
		(property "Author" "Antmicro"
			(at 264.16 59.69 0)
			(effects
				(font
					(size 1.27 1.27)
					(thickness 0.15)
				)
				(justify left bottom)
				(hide yes)
			)
		)
		(property "Voltage" "50V"
			(at 261.62 59.69 0)
			(effects
				(font
					(size 1.27 1.27)
				)
				(justify left bottom)
				(hide yes)
			)
		)
		(property "Dielectric" "X5R"
			(at 259.08 59.69 0)
			(effects
				(font
					(size 1.27 1.27)
				)
				(justify left bottom)
				(hide yes)
			)
		)
		(pin "1"
		)
		(pin "2"
		)
		(instances
			(project "cm4-baseboard"
				(path ""
					(reference "C922")
					(unit 1)
				)
			)
			(project "usb"
				(path ""
					(reference "C922")
					(unit 1)
				)
			)
		)
	)
	(symbol
		(lib_id "antmicroLogicTranslatorsLevelShifters:TXB0104_UQFN")
		(at 344.17 217.17 0)
		(unit 1)
		(exclude_from_sim no)
		(in_bom yes)
		(on_board yes)
		(dnp no)
		(fields_autoplaced yes)
		(property "Reference" "U907"
			(at 354.33 209.55 0)
			(effects
				(font
					(size 1.27 1.27)
					(thickness 0.15)
				)
			)
		)
		(property "Value" "TXB0104_UQFN"
			(at 354.33 212.09 0)
			(effects
				(font
					(size 1.27 1.27)
					(thickness 0.15)
				)
				(hide yes)
			)
		)
		(property "Footprint" "antmicro-footprints:UQFN-12_2x1.7mm_P0.4mm_Texas_RUT"
			(at 379.73 227.33 0)
			(effects
				(font
					(size 1.27 1.27)
					(thickness 0.15)
				)
				(justify left bottom)
				(hide yes)
			)
		)
		(property "Datasheet" "http://www.ti.com/lit/ds/symlink/txb0104.pdf"
			(at 379.73 229.87 0)
			(effects
				(font
					(size 1.27 1.27)
					(thickness 0.15)
				)
				(justify left bottom)
				(hide yes)
			)
		)
		(property "Description" ""
			(at 344.17 217.17 0)
			(effects
				(font
					(size 1.27 1.27)
				)
				(hide yes)
			)
		)
		(property "Manufacturer" "Texas Instruments"
			(at 379.73 232.41 0)
			(effects
				(font
					(size 1.27 1.27)
					(thickness 0.15)
				)
				(justify left bottom)
				(hide yes)
			)
		)
		(property "MPN" "TXB0104RUTR"
			(at 354.33 212.09 0)
			(effects
				(font
					(size 1.27 1.27)
					(thickness 0.15)
				)
			)
		)
		(property "Author" "Antmicro"
			(at 379.73 237.49 0)
			(effects
				(font
					(size 1.27 1.27)
					(thickness 0.15)
				)
				(justify left bottom)
				(hide yes)
			)
		)
		(property "License" "Apache-2.0"
			(at 379.73 240.03 0)
			(effects
				(font
					(size 1.27 1.27)
					(thickness 0.15)
				)
				(justify left bottom)
				(hide yes)
			)
		)
		(pin "1"
		)
		(pin "10"
		)
		(pin "11"
		)
		(pin "12"
		)
		(pin "2"
		)
		(pin "3"
		)
		(pin "4"
		)
		(pin "5"
		)
		(pin "6"
		)
		(pin "7"
		)
		(pin "8"
		)
		(pin "9"
		)
		(instances
			(project "cm4-baseboard"
				(path ""
					(reference "U907")
					(unit 1)
				)
			)
		)
	)
	(symbol
		(lib_id "antmicropower:+3V3")
		(at 367.03 176.53 0)
		(unit 1)
		(exclude_from_sim no)
		(in_bom yes)
		(on_board yes)
		(dnp no)
		(property "Reference" "#PWR014"
			(at 382.27 176.53 0)
			(effects
				(font
					(size 1.27 1.27)
					(thickness 0.15)
				)
				(justify left bottom)
				(hide yes)
			)
		)
		(property "Value" "+3V3"
			(at 367.03 172.72 0)
			(effects
				(font
					(size 1.27 1.27)
					(thickness 0.15)
				)
			)
		)
		(property "Footprint" ""
			(at 382.27 184.15 0)
			(effects
				(font
					(size 1.27 1.27)
					(thickness 0.15)
				)
				(justify left bottom)
				(hide yes)
			)
		)
		(property "Datasheet" ""
			(at 382.27 186.69 0)
			(effects
				(font
					(size 1.27 1.27)
					(thickness 0.15)
				)
				(justify left bottom)
				(hide yes)
			)
		)
		(property "Description" ""
			(at 367.03 176.53 0)
			(effects
				(font
					(size 1.27 1.27)
				)
				(hide yes)
			)
		)
		(property "Author" "Antmicro"
			(at 382.27 179.07 0)
			(effects
				(font
					(size 1.27 1.27)
					(thickness 0.15)
				)
				(justify left bottom)
				(hide yes)
			)
		)
		(property "License" "Apache-2.0"
			(at 382.27 181.61 0)
			(effects
				(font
					(size 1.27 1.27)
					(thickness 0.15)
				)
				(justify left bottom)
				(hide yes)
			)
		)
		(pin "1"
		)
		(instances
			(project "cm4-baseboard"
				(path ""
					(reference "#PWR014")
					(unit 1)
				)
			)
		)
	)
	(symbol
		(lib_id "antmicroResistors0402:R_10k_0402")
		(at 187.96 125.73 270)
		(unit 1)
		(exclude_from_sim no)
		(in_bom no)
		(on_board yes)
		(dnp yes)
		(property "Reference" "R908"
			(at 189.23 127.635 90)
			(effects
				(font
					(size 1.27 1.27)
				)
				(justify left)
			)
		)
		(property "Value" "R_10k_0402"
			(at 184.15 125.73 0)
			(effects
				(font
					(size 1.27 1.27)
					(thickness 0.15)
				)
				(justify left bottom)
				(hide yes)
			)
		)
		(property "Footprint" "antmicro-footprints:R_0402_1005Metric"
			(at 193.04 130.81 0)
			(effects
				(font
					(size 1.27 1.27)
					(thickness 0.15)
				)
				(justify left bottom)
				(hide yes)
			)
		)
		(property "Datasheet" "https://www.bourns.com/docs/product-datasheets/cr.pdf"
			(at 187.96 125.73 0)
			(effects
				(font
					(size 1.27 1.27)
					(thickness 0.15)
				)
				(justify left bottom)
				(hide yes)
			)
		)
		(property "Description" ""
			(at 187.96 125.73 0)
			(effects
				(font
					(size 1.27 1.27)
				)
				(hide yes)
			)
		)
		(property "Manufacturer" "Bourns"
			(at 198.12 130.81 0)
			(effects
				(font
					(size 1.27 1.27)
					(thickness 0.15)
				)
				(justify left bottom)
				(hide yes)
			)
		)
		(property "MPN" "CR0402-FX-1002GLF"
			(at 195.58 130.81 0)
			(effects
				(font
					(size 1.27 1.27)
					(thickness 0.15)
				)
				(justify left bottom)
				(hide yes)
			)
		)
		(property "Val" "10k"
			(at 189.23 129.5399 90)
			(effects
				(font
					(size 1.27 1.27)
					(thickness 0.15)
				)
				(justify left)
			)
		)
		(property "License" "Apache-2.0"
			(at 162.56 146.05 0)
			(effects
				(font
					(size 1.27 1.27)
					(thickness 0.15)
				)
				(justify left bottom)
				(hide yes)
			)
		)
		(property "Author" "Antmicro"
			(at 160.02 146.05 0)
			(effects
				(font
					(size 1.27 1.27)
					(thickness 0.15)
				)
				(justify left bottom)
				(hide yes)
			)
		)
		(property "Tolerance" "1%"
			(at 177.8 146.05 0)
			(effects
				(font
					(size 1.27 1.27)
				)
				(justify left bottom)
				(hide yes)
			)
		)
		(pin "1"
		)
		(pin "2"
		)
		(instances
			(project "cm4-baseboard"
				(path ""
					(reference "R908")
					(unit 1)
				)
			)
			(project "usb"
				(path ""
					(reference "R908")
					(unit 1)
				)
			)
		)
	)
	(symbol
		(lib_id "antmicroResonators:Resonator_12MHz_ABM8G")
		(at 320.04 132.08 0)
		(unit 1)
		(exclude_from_sim no)
		(in_bom yes)
		(on_board yes)
		(dnp no)
		(property "Reference" "Y901"
			(at 323.85 125.73 0)
			(effects
				(font
					(size 1.27 1.27)
				)
			)
		)
		(property "Value" "Resonator_12MHz_ABM8G"
			(at 323.85 126.238 0)
			(effects
				(font
					(size 1.27 1.27)
					(thickness 0.15)
				)
				(hide yes)
			)
		)
		(property "Footprint" "antmicro-footprints:Resonator_SMD_Abracon_ABM8G_3.2x2.5mm"
			(at 335.28 147.32 0)
			(effects
				(font
					(size 1.27 1.27)
					(thickness 0.15)
				)
				(justify left bottom)
				(hide yes)
			)
		)
		(property "Datasheet" "https://abracon.com/Resonators/ABM8G.pdf"
			(at 335.28 149.86 0)
			(effects
				(font
					(size 1.27 1.27)
					(thickness 0.15)
				)
				(justify left bottom)
				(hide yes)
			)
		)
		(property "Description" ""
			(at 320.04 132.08 0)
			(effects
				(font
					(size 1.27 1.27)
				)
				(hide yes)
			)
		)
		(property "MPN" "ABM8G-12.000MHZ-18-D2Y-T"
			(at 335.28 139.7 0)
			(effects
				(font
					(size 1.27 1.27)
					(thickness 0.15)
				)
				(justify left bottom)
				(hide yes)
			)
		)
		(property "Manufacturer" "Abracon"
			(at 335.28 152.4 0)
			(effects
				(font
					(size 1.27 1.27)
					(thickness 0.15)
				)
				(justify left bottom)
				(hide yes)
			)
		)
		(property "Val" "12 MHz"
			(at 323.85 128.27 0)
			(effects
				(font
					(size 1.27 1.27)
					(thickness 0.15)
				)
			)
		)
		(property "Author" "Antmicro"
			(at 335.28 154.94 0)
			(effects
				(font
					(size 1.27 1.27)
					(thickness 0.15)
				)
				(justify left bottom)
				(hide yes)
			)
		)
		(property "License" "Apache-2.0"
			(at 335.28 157.48 0)
			(effects
				(font
					(size 1.27 1.27)
					(thickness 0.15)
				)
				(justify left bottom)
				(hide yes)
			)
		)
		(pin "1"
		)
		(pin "2"
		)
		(pin "3"
		)
		(pin "4"
		)
		(instances
			(project "cm4-baseboard"
				(path ""
					(reference "Y901")
					(unit 1)
				)
			)
			(project "usb"
				(path ""
					(reference "Y901")
					(unit 1)
				)
			)
		)
	)
	(symbol
		(lib_id "antmicropower:GND")
		(at 160.02 68.58 0)
		(unit 1)
		(exclude_from_sim no)
		(in_bom yes)
		(on_board yes)
		(dnp no)
		(fields_autoplaced yes)
		(property "Reference" "#PWR0919"
			(at 168.91 71.12 0)
			(effects
				(font
					(size 1.27 1.27)
					(thickness 0.15)
				)
				(justify left bottom)
				(hide yes)
			)
		)
		(property "Value" "GND"
			(at 158.0098 73.66 0)
			(effects
				(font
					(size 1.27 1.27)
					(thickness 0.15)
				)
				(justify left bottom)
			)
		)
		(property "Footprint" ""
			(at 168.91 76.2 0)
			(effects
				(font
					(size 1.27 1.27)
					(thickness 0.15)
				)
				(justify left bottom)
				(hide yes)
			)
		)
		(property "Datasheet" ""
			(at 168.91 81.28 0)
			(effects
				(font
					(size 1.27 1.27)
					(thickness 0.15)
				)
				(justify left bottom)
				(hide yes)
			)
		)
		(property "Description" ""
			(at 160.02 68.58 0)
			(effects
				(font
					(size 1.27 1.27)
				)
				(hide yes)
			)
		)
		(property "Author" "Antmicro"
			(at 168.91 76.2 0)
			(effects
				(font
					(size 1.27 1.27)
					(thickness 0.15)
				)
				(justify left bottom)
				(hide yes)
			)
		)
		(property "License" "Apache-2.0"
			(at 168.91 78.74 0)
			(effects
				(font
					(size 1.27 1.27)
					(thickness 0.15)
				)
				(justify left bottom)
				(hide yes)
			)
		)
		(pin "1"
		)
		(instances
			(project "cm4-baseboard"
				(path ""
					(reference "#PWR0919")
					(unit 1)
				)
			)
			(project "usb"
				(path ""
					(reference "#PWR0919")
					(unit 1)
				)
			)
		)
	)
	(symbol
		(lib_id "antmicroCapacitors0402:C_100n_0402")
		(at 281.94 55.88 270)
		(unit 1)
		(exclude_from_sim no)
		(in_bom yes)
		(on_board yes)
		(dnp no)
		(fields_autoplaced yes)
		(property "Reference" "C919"
			(at 284.48 57.1563 90)
			(effects
				(font
					(size 1.27 1.27)
				)
				(justify left)
			)
		)
		(property "Value" "C_100n_0402"
			(at 278.13 55.88 0)
			(effects
				(font
					(size 1.27 1.27)
					(thickness 0.15)
				)
				(justify left bottom)
				(hide yes)
			)
		)
		(property "Footprint" "antmicro-footprints:C_0402_1005Metric"
			(at 287.02 60.96 0)
			(effects
				(font
					(size 1.27 1.27)
					(thickness 0.15)
				)
				(justify left bottom)
				(hide yes)
			)
		)
		(property "Datasheet" "https://www.murata.com/products/productdetail?partno=GRM155R61H104KE14%23"
			(at 281.94 55.88 0)
			(effects
				(font
					(size 1.27 1.27)
					(thickness 0.15)
				)
				(justify left bottom)
				(hide yes)
			)
		)
		(property "Description" ""
			(at 281.94 55.88 0)
			(effects
				(font
					(size 1.27 1.27)
				)
				(hide yes)
			)
		)
		(property "Manufacturer" "Murata"
			(at 292.1 60.96 0)
			(effects
				(font
					(size 1.27 1.27)
					(thickness 0.15)
				)
				(justify left bottom)
				(hide yes)
			)
		)
		(property "MPN" "GRM155R61H104KE14D"
			(at 289.56 60.96 0)
			(effects
				(font
					(size 1.27 1.27)
					(thickness 0.15)
				)
				(justify left bottom)
				(hide yes)
			)
		)
		(property "Val" "100n"
			(at 284.48 60.3312 90)
			(effects
				(font
					(size 1.27 1.27)
					(thickness 0.15)
				)
				(justify left)
			)
		)
		(property "License" "Apache-2.0"
			(at 259.08 76.2 0)
			(effects
				(font
					(size 1.27 1.27)
					(thickness 0.15)
				)
				(justify left bottom)
				(hide yes)
			)
		)
		(property "Author" "Antmicro"
			(at 256.54 76.2 0)
			(effects
				(font
					(size 1.27 1.27)
					(thickness 0.15)
				)
				(justify left bottom)
				(hide yes)
			)
		)
		(property "Voltage" "50V"
			(at 254 76.2 0)
			(effects
				(font
					(size 1.27 1.27)
				)
				(justify left bottom)
				(hide yes)
			)
		)
		(property "Dielectric" "X5R"
			(at 251.46 76.2 0)
			(effects
				(font
					(size 1.27 1.27)
				)
				(justify left bottom)
				(hide yes)
			)
		)
		(pin "1"
		)
		(pin "2"
		)
		(instances
			(project "cm4-baseboard"
				(path ""
					(reference "C919")
					(unit 1)
				)
			)
			(project "usb"
				(path ""
					(reference "C919")
					(unit 1)
				)
			)
		)
	)
	(symbol
		(lib_id "antmicropower:+3V3")
		(at 172.72 243.84 0)
		(unit 1)
		(exclude_from_sim no)
		(in_bom yes)
		(on_board yes)
		(dnp no)
		(fields_autoplaced yes)
		(property "Reference" "#PWR07"
			(at 187.96 243.84 0)
			(effects
				(font
					(size 1.27 1.27)
					(thickness 0.15)
				)
				(justify left bottom)
				(hide yes)
			)
		)
		(property "Value" "+3V3"
			(at 172.72 240.03 0)
			(effects
				(font
					(size 1.27 1.27)
					(thickness 0.15)
				)
			)
		)
		(property "Footprint" ""
			(at 187.96 251.46 0)
			(effects
				(font
					(size 1.27 1.27)
					(thickness 0.15)
				)
				(justify left bottom)
				(hide yes)
			)
		)
		(property "Datasheet" ""
			(at 187.96 254 0)
			(effects
				(font
					(size 1.27 1.27)
					(thickness 0.15)
				)
				(justify left bottom)
				(hide yes)
			)
		)
		(property "Description" ""
			(at 172.72 243.84 0)
			(effects
				(font
					(size 1.27 1.27)
				)
				(hide yes)
			)
		)
		(property "Author" "Antmicro"
			(at 187.96 246.38 0)
			(effects
				(font
					(size 1.27 1.27)
					(thickness 0.15)
				)
				(justify left bottom)
				(hide yes)
			)
		)
		(property "License" "Apache-2.0"
			(at 187.96 248.92 0)
			(effects
				(font
					(size 1.27 1.27)
					(thickness 0.15)
				)
				(justify left bottom)
				(hide yes)
			)
		)
		(pin "1"
		)
		(instances
			(project "cm4-baseboard"
				(path ""
					(reference "#PWR07")
					(unit 1)
				)
			)
			(project "usb"
				(path ""
					(reference "#PWR07")
					(unit 1)
				)
			)
		)
	)
	(symbol
		(lib_id "antmicropower:GND")
		(at 297.18 45.72 0)
		(unit 1)
		(exclude_from_sim no)
		(in_bom yes)
		(on_board yes)
		(dnp no)
		(property "Reference" "#PWR0947"
			(at 297.18 52.07 0)
			(effects
				(font
					(size 1.27 1.27)
				)
				(hide yes)
			)
		)
		(property "Value" "GND"
			(at 297.18 49.53 0)
			(effects
				(font
					(size 1.27 1.27)
				)
			)
		)
		(property "Footprint" ""
			(at 306.07 53.34 0)
			(effects
				(font
					(size 1.27 1.27)
					(thickness 0.15)
				)
				(justify left bottom)
				(hide yes)
			)
		)
		(property "Datasheet" ""
			(at 306.07 58.42 0)
			(effects
				(font
					(size 1.27 1.27)
					(thickness 0.15)
				)
				(justify left bottom)
				(hide yes)
			)
		)
		(property "Description" ""
			(at 297.18 45.72 0)
			(effects
				(font
					(size 1.27 1.27)
				)
				(hide yes)
			)
		)
		(property "Author" "Antmicro"
			(at 306.07 53.34 0)
			(effects
				(font
					(size 1.27 1.27)
					(thickness 0.15)
				)
				(justify left bottom)
				(hide yes)
			)
		)
		(property "License" "Apache-2.0"
			(at 306.07 55.88 0)
			(effects
				(font
					(size 1.27 1.27)
					(thickness 0.15)
				)
				(justify left bottom)
				(hide yes)
			)
		)
		(pin "1"
		)
		(instances
			(project "cm4-baseboard"
				(path ""
					(reference "#PWR0947")
					(unit 1)
				)
			)
			(project "usb"
				(path ""
					(reference "#PWR0947")
					(unit 1)
				)
			)
		)
	)
	(symbol
		(lib_id "antmicroCapacitors0402:C_100n_0402")
		(at 285.75 149.86 270)
		(unit 1)
		(exclude_from_sim no)
		(in_bom yes)
		(on_board yes)
		(dnp no)
		(property "Reference" "C921"
			(at 286.385 150.495 90)
			(effects
				(font
					(size 1.27 1.27)
				)
				(justify left)
			)
		)
		(property "Value" "C_100n_0402"
			(at 281.94 149.86 0)
			(effects
				(font
					(size 1.27 1.27)
					(thickness 0.15)
				)
				(justify left bottom)
				(hide yes)
			)
		)
		(property "Footprint" "antmicro-footprints:C_0402_1005Metric"
			(at 290.83 154.94 0)
			(effects
				(font
					(size 1.27 1.27)
					(thickness 0.15)
				)
				(justify left bottom)
				(hide yes)
			)
		)
		(property "Datasheet" "https://www.murata.com/products/productdetail?partno=GRM155R61H104KE14%23"
			(at 285.75 149.86 0)
			(effects
				(font
					(size 1.27 1.27)
					(thickness 0.15)
				)
				(justify left bottom)
				(hide yes)
			)
		)
		(property "Description" ""
			(at 285.75 149.86 0)
			(effects
				(font
					(size 1.27 1.27)
				)
				(hide yes)
			)
		)
		(property "Manufacturer" "Murata"
			(at 295.91 154.94 0)
			(effects
				(font
					(size 1.27 1.27)
					(thickness 0.15)
				)
				(justify left bottom)
				(hide yes)
			)
		)
		(property "MPN" "GRM155R61H104KE14D"
			(at 293.37 154.94 0)
			(effects
				(font
					(size 1.27 1.27)
					(thickness 0.15)
				)
				(justify left bottom)
				(hide yes)
			)
		)
		(property "Val" "100n"
			(at 286.385 154.305 90)
			(effects
				(font
					(size 1.27 1.27)
					(thickness 0.15)
				)
				(justify left)
			)
		)
		(property "License" "Apache-2.0"
			(at 262.89 170.18 0)
			(effects
				(font
					(size 1.27 1.27)
					(thickness 0.15)
				)
				(justify left bottom)
				(hide yes)
			)
		)
		(property "Author" "Antmicro"
			(at 260.35 170.18 0)
			(effects
				(font
					(size 1.27 1.27)
					(thickness 0.15)
				)
				(justify left bottom)
				(hide yes)
			)
		)
		(property "Voltage" "50V"
			(at 257.81 170.18 0)
			(effects
				(font
					(size 1.27 1.27)
				)
				(justify left bottom)
				(hide yes)
			)
		)
		(property "Dielectric" "X5R"
			(at 255.27 170.18 0)
			(effects
				(font
					(size 1.27 1.27)
				)
				(justify left bottom)
				(hide yes)
			)
		)
		(pin "1"
		)
		(pin "2"
		)
		(instances
			(project "cm4-baseboard"
				(path ""
					(reference "C921")
					(unit 1)
				)
			)
			(project "usb"
				(path ""
					(reference "C921")
					(unit 1)
				)
			)
		)
	)
	(symbol
		(lib_id "antmicroTransistorsFETsMOSFETsSingle:PJE138K")
		(at 127 74.93 0)
		(mirror y)
		(unit 1)
		(exclude_from_sim no)
		(in_bom yes)
		(on_board yes)
		(dnp no)
		(property "Reference" "Q904"
			(at 130.81 67.31 0)
			(effects
				(font
					(size 1.27 1.27)
				)
				(justify left)
			)
		)
		(property "Value" "PJE138K"
			(at 134.62 69.85 0)
			(effects
				(font
					(size 1.27 1.27)
				)
				(justify left)
			)
		)
		(property "Footprint" "antmicro-footprints:SOT-523"
			(at 121.92 69.85 0)
			(effects
				(font
					(size 1.524 1.524)
				)
				(justify left bottom)
				(hide yes)
			)
		)
		(property "Datasheet" "https://www.mouser.com/datasheet/2/1057/PJE138K-1876698.pdf"
			(at 121.92 67.31 0)
			(effects
				(font
					(size 1.524 1.524)
				)
				(justify left bottom)
				(hide yes)
			)
		)
		(property "Description" ""
			(at 127 74.93 0)
			(effects
				(font
					(size 1.27 1.27)
				)
				(hide yes)
			)
		)
		(property "MPN" "PJE138K_R1_00001"
			(at 110.49 64.77 0)
			(effects
				(font
					(size 1.524 1.524)
				)
				(justify left bottom)
				(hide yes)
			)
		)
		(property "Manufacturer" "PANJIT"
			(at 121.92 64.77 0)
			(effects
				(font
					(size 1.524 1.524)
				)
				(justify left bottom)
				(hide yes)
			)
		)
		(property "Author" "Antmicro"
			(at 104.14 96.52 0)
			(effects
				(font
					(size 1.27 1.27)
					(thickness 0.15)
				)
				(justify left bottom)
				(hide yes)
			)
		)
		(property "License" "Apache-2.0"
			(at 104.14 99.06 0)
			(effects
				(font
					(size 1.27 1.27)
					(thickness 0.15)
				)
				(justify left bottom)
				(hide yes)
			)
		)
		(pin "1"
		)
		(pin "2"
		)
		(pin "3"
		)
		(instances
			(project "cm4-baseboard"
				(path ""
					(reference "Q904")
					(unit 1)
				)
			)
			(project "usb"
				(path ""
					(reference "Q904")
					(unit 1)
				)
			)
		)
	)
	(symbol
		(lib_id "antmicropower:GND")
		(at 317.5 138.43 0)
		(unit 1)
		(exclude_from_sim no)
		(in_bom yes)
		(on_board yes)
		(dnp no)
		(fields_autoplaced yes)
		(property "Reference" "#PWR0949"
			(at 317.5 144.78 0)
			(effects
				(font
					(size 1.27 1.27)
				)
				(hide yes)
			)
		)
		(property "Value" "GND"
			(at 317.5 142.875 0)
			(effects
				(font
					(size 1.27 1.27)
				)
			)
		)
		(property "Footprint" ""
			(at 326.39 146.05 0)
			(effects
				(font
					(size 1.27 1.27)
					(thickness 0.15)
				)
				(justify left bottom)
				(hide yes)
			)
		)
		(property "Datasheet" ""
			(at 326.39 151.13 0)
			(effects
				(font
					(size 1.27 1.27)
					(thickness 0.15)
				)
				(justify left bottom)
				(hide yes)
			)
		)
		(property "Description" ""
			(at 317.5 138.43 0)
			(effects
				(font
					(size 1.27 1.27)
				)
				(hide yes)
			)
		)
		(property "Author" "Antmicro"
			(at 326.39 146.05 0)
			(effects
				(font
					(size 1.27 1.27)
					(thickness 0.15)
				)
				(justify left bottom)
				(hide yes)
			)
		)
		(property "License" "Apache-2.0"
			(at 326.39 148.59 0)
			(effects
				(font
					(size 1.27 1.27)
					(thickness 0.15)
				)
				(justify left bottom)
				(hide yes)
			)
		)
		(pin "1"
		)
		(instances
			(project "cm4-baseboard"
				(path ""
					(reference "#PWR0949")
					(unit 1)
				)
			)
			(project "usb"
				(path ""
					(reference "#PWR0949")
					(unit 1)
				)
			)
		)
	)
	(symbol
		(lib_id "antmicropower:GND")
		(at 234.95 72.39 0)
		(unit 1)
		(exclude_from_sim no)
		(in_bom yes)
		(on_board yes)
		(dnp no)
		(fields_autoplaced yes)
		(property "Reference" "#PWR0918"
			(at 243.84 74.93 0)
			(effects
				(font
					(size 1.27 1.27)
					(thickness 0.15)
				)
				(justify left bottom)
				(hide yes)
			)
		)
		(property "Value" "GND"
			(at 232.9398 77.47 0)
			(effects
				(font
					(size 1.27 1.27)
					(thickness 0.15)
				)
				(justify left bottom)
			)
		)
		(property "Footprint" ""
			(at 243.84 80.01 0)
			(effects
				(font
					(size 1.27 1.27)
					(thickness 0.15)
				)
				(justify left bottom)
				(hide yes)
			)
		)
		(property "Datasheet" ""
			(at 243.84 85.09 0)
			(effects
				(font
					(size 1.27 1.27)
					(thickness 0.15)
				)
				(justify left bottom)
				(hide yes)
			)
		)
		(property "Description" ""
			(at 234.95 72.39 0)
			(effects
				(font
					(size 1.27 1.27)
				)
				(hide yes)
			)
		)
		(property "Author" "Antmicro"
			(at 243.84 80.01 0)
			(effects
				(font
					(size 1.27 1.27)
					(thickness 0.15)
				)
				(justify left bottom)
				(hide yes)
			)
		)
		(property "License" "Apache-2.0"
			(at 243.84 82.55 0)
			(effects
				(font
					(size 1.27 1.27)
					(thickness 0.15)
				)
				(justify left bottom)
				(hide yes)
			)
		)
		(pin "1"
		)
		(instances
			(project "cm4-baseboard"
				(path ""
					(reference "#PWR0918")
					(unit 1)
				)
			)
		)
	)
	(symbol
		(lib_id "antmicroCapacitors0402:C_18p_0402")
		(at 330.2 133.35 270)
		(unit 1)
		(exclude_from_sim no)
		(in_bom yes)
		(on_board yes)
		(dnp no)
		(fields_autoplaced yes)
		(property "Reference" "C927"
			(at 332.74 134.6263 90)
			(effects
				(font
					(size 1.27 1.27)
				)
				(justify left)
			)
		)
		(property "Value" "C_18p_0402"
			(at 326.39 133.35 0)
			(effects
				(font
					(size 1.27 1.27)
					(thickness 0.15)
				)
				(justify left bottom)
				(hide yes)
			)
		)
		(property "Footprint" "antmicro-footprints:C_0402_1005Metric"
			(at 335.28 138.43 0)
			(effects
				(font
					(size 1.27 1.27)
					(thickness 0.15)
				)
				(justify left bottom)
				(hide yes)
			)
		)
		(property "Datasheet" "https://product.samsungsem.com/mlcc/CL05C180JB51PN.do"
			(at 330.2 133.35 0)
			(effects
				(font
					(size 1.27 1.27)
					(thickness 0.15)
				)
				(justify left bottom)
				(hide yes)
			)
		)
		(property "Description" ""
			(at 330.2 133.35 0)
			(effects
				(font
					(size 1.27 1.27)
				)
				(hide yes)
			)
		)
		(property "Manufacturer" "Samsung Electro-Mechanics"
			(at 340.36 138.43 0)
			(effects
				(font
					(size 1.27 1.27)
					(thickness 0.15)
				)
				(justify left bottom)
				(hide yes)
			)
		)
		(property "MPN" "CL05C180JB51PNC"
			(at 337.82 138.43 0)
			(effects
				(font
					(size 1.27 1.27)
					(thickness 0.15)
				)
				(justify left bottom)
				(hide yes)
			)
		)
		(property "Val" "18p"
			(at 332.74 137.8012 90)
			(effects
				(font
					(size 1.27 1.27)
					(thickness 0.15)
				)
				(justify left)
			)
		)
		(property "License" "Apache-2.0"
			(at 307.34 153.67 0)
			(effects
				(font
					(size 1.27 1.27)
					(thickness 0.15)
				)
				(justify left bottom)
				(hide yes)
			)
		)
		(property "Author" "Antmicro"
			(at 304.8 153.67 0)
			(effects
				(font
					(size 1.27 1.27)
					(thickness 0.15)
				)
				(justify left bottom)
				(hide yes)
			)
		)
		(property "Voltage" ""
			(at 302.26 153.67 0)
			(effects
				(font
					(size 1.27 1.27)
				)
				(justify left bottom)
				(hide yes)
			)
		)
		(property "Dielectric" ""
			(at 299.72 153.67 0)
			(effects
				(font
					(size 1.27 1.27)
				)
				(justify left bottom)
				(hide yes)
			)
		)
		(pin "1"
		)
		(pin "2"
		)
		(instances
			(project "cm4-baseboard"
				(path ""
					(reference "C927")
					(unit 1)
				)
			)
			(project "usb"
				(path ""
					(reference "C927")
					(unit 1)
				)
			)
		)
	)
	(symbol
		(lib_id "antmicropower:+5V")
		(at 247.65 182.88 0)
		(unit 1)
		(exclude_from_sim no)
		(in_bom yes)
		(on_board yes)
		(dnp no)
		(fields_autoplaced yes)
		(property "Reference" "#PWR09"
			(at 262.89 185.42 0)
			(effects
				(font
					(size 1.27 1.27)
					(thickness 0.15)
				)
				(justify left bottom)
				(hide yes)
			)
		)
		(property "Value" "+5V"
			(at 247.65 179.07 0)
			(effects
				(font
					(size 1.27 1.27)
					(thickness 0.15)
				)
			)
		)
		(property "Footprint" ""
			(at 262.89 190.5 0)
			(effects
				(font
					(size 1.27 1.27)
					(thickness 0.15)
				)
				(justify left bottom)
				(hide yes)
			)
		)
		(property "Datasheet" ""
			(at 262.89 193.04 0)
			(effects
				(font
					(size 1.27 1.27)
					(thickness 0.15)
				)
				(justify left bottom)
				(hide yes)
			)
		)
		(property "Description" ""
			(at 247.65 182.88 0)
			(effects
				(font
					(size 1.27 1.27)
				)
				(hide yes)
			)
		)
		(property "Author" "Antmicro"
			(at 262.89 190.5 0)
			(effects
				(font
					(size 1.27 1.27)
					(thickness 0.15)
				)
				(justify left bottom)
				(hide yes)
			)
		)
		(property "License" "Apache-2.0"
			(at 262.89 193.04 0)
			(effects
				(font
					(size 1.27 1.27)
					(thickness 0.15)
				)
				(justify left bottom)
				(hide yes)
			)
		)
		(pin "1"
		)
		(instances
			(project "cm4-baseboard"
				(path ""
					(reference "#PWR09")
					(unit 1)
				)
			)
			(project "usb"
				(path ""
					(reference "#PWR09")
					(unit 1)
				)
			)
		)
	)
	(symbol
		(lib_id "antmicroMemory:93AA66C_SOIC")
		(at 160.02 133.35 0)
		(unit 1)
		(exclude_from_sim no)
		(in_bom yes)
		(on_board yes)
		(dnp no)
		(fields_autoplaced yes)
		(property "Reference" "U902"
			(at 168.275 125.73 0)
			(effects
				(font
					(size 1.27 1.27)
				)
			)
		)
		(property "Value" "93AA66C_SOIC"
			(at 168.275 128.27 0)
			(effects
				(font
					(size 1.27 1.27)
					(thickness 0.15)
				)
				(hide yes)
			)
		)
		(property "Footprint" "antmicro-footprints:SOIC-8_3.9x4.9x1.75mm_P1.27mm"
			(at 195.58 143.51 0)
			(effects
				(font
					(size 1.27 1.27)
					(thickness 0.15)
				)
				(justify left bottom)
				(hide yes)
			)
		)
		(property "Datasheet" "https://ww1.microchip.com/downloads/aemDocuments/documents/MPD/ProductDocuments/DataSheets/93AA66X-93LC66X-93C66X-4-Kbit-Microwire-Compatible-Serial-EEPROM-Data-Sheet.pdf"
			(at 195.58 146.05 0)
			(effects
				(font
					(size 1.27 1.27)
					(thickness 0.15)
				)
				(justify left bottom)
				(hide yes)
			)
		)
		(property "Description" ""
			(at 160.02 133.35 0)
			(effects
				(font
					(size 1.27 1.27)
				)
				(hide yes)
			)
		)
		(property "MPN" "93AA66C-I/SN"
			(at 168.275 128.27 0)
			(effects
				(font
					(size 1.27 1.27)
				)
			)
		)
		(property "Manufacturer" "Microchip Technology"
			(at 195.58 152.4 0)
			(effects
				(font
					(size 1.27 1.27)
				)
				(justify left)
				(hide yes)
			)
		)
		(property "Author" "Antmicro"
			(at 195.58 148.59 0)
			(effects
				(font
					(size 1.27 1.27)
					(thickness 0.15)
				)
				(justify left bottom)
				(hide yes)
			)
		)
		(property "License" "Apache-2.0"
			(at 195.58 151.13 0)
			(effects
				(font
					(size 1.27 1.27)
					(thickness 0.15)
				)
				(justify left bottom)
				(hide yes)
			)
		)
		(pin "1"
		)
		(pin "2"
		)
		(pin "3"
		)
		(pin "4"
		)
		(pin "5"
		)
		(pin "6"
		)
		(pin "7"
		)
		(pin "8"
		)
		(instances
			(project "cm4-baseboard"
				(path ""
					(reference "U902")
					(unit 1)
				)
			)
			(project "usb"
				(path ""
					(reference "U902")
					(unit 1)
				)
			)
		)
	)
	(symbol
		(lib_id "antmicropower:GND")
		(at 262.89 156.21 0)
		(unit 1)
		(exclude_from_sim no)
		(in_bom yes)
		(on_board yes)
		(dnp no)
		(fields_autoplaced yes)
		(property "Reference" "#PWR0935"
			(at 262.89 162.56 0)
			(effects
				(font
					(size 1.27 1.27)
				)
				(hide yes)
			)
		)
		(property "Value" "GND"
			(at 262.89 161.29 0)
			(effects
				(font
					(size 1.27 1.27)
				)
			)
		)
		(property "Footprint" ""
			(at 271.78 163.83 0)
			(effects
				(font
					(size 1.27 1.27)
					(thickness 0.15)
				)
				(justify left bottom)
				(hide yes)
			)
		)
		(property "Datasheet" ""
			(at 271.78 168.91 0)
			(effects
				(font
					(size 1.27 1.27)
					(thickness 0.15)
				)
				(justify left bottom)
				(hide yes)
			)
		)
		(property "Description" ""
			(at 262.89 156.21 0)
			(effects
				(font
					(size 1.27 1.27)
				)
				(hide yes)
			)
		)
		(property "Author" "Antmicro"
			(at 271.78 163.83 0)
			(effects
				(font
					(size 1.27 1.27)
					(thickness 0.15)
				)
				(justify left bottom)
				(hide yes)
			)
		)
		(property "License" "Apache-2.0"
			(at 271.78 166.37 0)
			(effects
				(font
					(size 1.27 1.27)
					(thickness 0.15)
				)
				(justify left bottom)
				(hide yes)
			)
		)
		(pin "1"
		)
		(instances
			(project "cm4-baseboard"
				(path ""
					(reference "#PWR0935")
					(unit 1)
				)
			)
			(project "usb"
				(path ""
					(reference "#PWR0935")
					(unit 1)
				)
			)
		)
	)
	(symbol
		(lib_id "antmicropower:GND")
		(at 384.81 207.01 0)
		(unit 1)
		(exclude_from_sim no)
		(in_bom yes)
		(on_board yes)
		(dnp no)
		(property "Reference" "#PWR022"
			(at 393.7 209.55 0)
			(effects
				(font
					(size 1.27 1.27)
					(thickness 0.15)
				)
				(justify left bottom)
				(hide yes)
			)
		)
		(property "Value" "GND"
			(at 384.81 211.455 0)
			(effects
				(font
					(size 1.27 1.27)
					(thickness 0.15)
				)
			)
		)
		(property "Footprint" ""
			(at 393.7 214.63 0)
			(effects
				(font
					(size 1.27 1.27)
					(thickness 0.15)
				)
				(justify left bottom)
				(hide yes)
			)
		)
		(property "Datasheet" ""
			(at 393.7 219.71 0)
			(effects
				(font
					(size 1.27 1.27)
					(thickness 0.15)
				)
				(justify left bottom)
				(hide yes)
			)
		)
		(property "Description" ""
			(at 384.81 207.01 0)
			(effects
				(font
					(size 1.27 1.27)
				)
				(hide yes)
			)
		)
		(property "Author" "Antmicro"
			(at 393.7 214.63 0)
			(effects
				(font
					(size 1.27 1.27)
					(thickness 0.15)
				)
				(justify left bottom)
				(hide yes)
			)
		)
		(property "License" "Apache-2.0"
			(at 393.7 217.17 0)
			(effects
				(font
					(size 1.27 1.27)
					(thickness 0.15)
				)
				(justify left bottom)
				(hide yes)
			)
		)
		(pin "1"
		)
		(instances
			(project "cm4-baseboard"
				(path ""
					(reference "#PWR022")
					(unit 1)
				)
			)
		)
	)
	(symbol
		(lib_id "antmicroCapacitorspol:C_Pol_330u_6.3V_KEMET-T520-B")
		(at 194.31 186.69 90)
		(mirror x)
		(unit 1)
		(exclude_from_sim no)
		(in_bom yes)
		(on_board yes)
		(dnp no)
		(fields_autoplaced yes)
		(property "Reference" "C929"
			(at 191.77 187.4266 90)
			(effects
				(font
					(size 1.27 1.27)
					(thickness 0.15)
				)
				(justify left)
			)
		)
		(property "Value" "C_Pol_330u_6.3V_KEMET-T520-B"
			(at 196.85 200.66 0)
			(effects
				(font
					(size 1.27 1.27)
					(thickness 0.15)
				)
				(justify left bottom)
				(hide yes)
			)
		)
		(property "Footprint" "antmicro-footprints:C_Pol_EIA-B"
			(at 201.93 200.66 0)
			(effects
				(font
					(size 1.27 1.27)
					(thickness 0.15)
				)
				(justify left bottom)
				(hide yes)
			)
		)
		(property "Datasheet" "https://www.kemet.com/en/us/capacitors/product/T520B337M006ATE040.html"
			(at 204.47 200.66 0)
			(effects
				(font
					(size 1.27 1.27)
					(thickness 0.15)
				)
				(justify left bottom)
				(hide yes)
			)
		)
		(property "Description" ""
			(at 194.31 186.69 0)
			(effects
				(font
					(size 1.27 1.27)
				)
				(hide yes)
			)
		)
		(property "Val" "330u"
			(at 191.77 189.9666 90)
			(effects
				(font
					(size 1.27 1.27)
					(thickness 0.15)
				)
				(justify left)
			)
		)
		(property "MPN" "T520B337M006ATE040"
			(at 207.01 200.66 0)
			(effects
				(font
					(size 1.27 1.27)
					(thickness 0.15)
				)
				(justify left bottom)
				(hide yes)
			)
		)
		(property "Manufacturer" "KEMET"
			(at 209.55 200.66 0)
			(effects
				(font
					(size 1.27 1.27)
					(thickness 0.15)
				)
				(justify left bottom)
				(hide yes)
			)
		)
		(property "License" "Apache-2.0"
			(at 212.09 200.66 0)
			(effects
				(font
					(size 1.27 1.27)
					(thickness 0.15)
				)
				(justify left bottom)
				(hide yes)
			)
		)
		(property "Author" "Antmicro"
			(at 214.63 200.66 0)
			(effects
				(font
					(size 1.27 1.27)
					(thickness 0.15)
				)
				(justify left bottom)
				(hide yes)
			)
		)
		(property "Voltage" "6.3V"
			(at 217.17 200.66 0)
			(effects
				(font
					(size 1.27 1.27)
				)
				(justify left bottom)
				(hide yes)
			)
		)
		(property "Dielectric" "template_dielectric"
			(at 219.71 200.66 0)
			(effects
				(font
					(size 1.27 1.27)
				)
				(justify left bottom)
				(hide yes)
			)
		)
		(pin "2"
		)
		(pin "1"
		)
		(instances
			(project "cm4-baseboard"
				(path ""
					(reference "C929")
					(unit 1)
				)
			)
			(project "usb"
				(path ""
					(reference "C929")
					(unit 1)
				)
			)
		)
	)
	(symbol
		(lib_id "antmicroCapacitors0402:C_10u_0402")
		(at 92.71 204.47 270)
		(mirror x)
		(unit 1)
		(exclude_from_sim no)
		(in_bom yes)
		(on_board yes)
		(dnp no)
		(property "Reference" "C908"
			(at 93.98 199.39 90)
			(effects
				(font
					(size 1.27 1.27)
					(thickness 0.15)
				)
				(justify left)
			)
		)
		(property "Value" "C_10u_0402"
			(at 82.55 184.15 0)
			(effects
				(font
					(size 1.27 1.27)
					(thickness 0.15)
				)
				(justify left bottom)
				(hide yes)
			)
		)
		(property "Footprint" "antmicro-footprints:C_0402_1005Metric"
			(at 80.01 184.15 0)
			(effects
				(font
					(size 1.27 1.27)
					(thickness 0.15)
				)
				(justify left bottom)
				(hide yes)
			)
		)
		(property "Datasheet" "https://www.yageo.com/en/Chart/Download/pdf/CC0402MRX5R5BB106"
			(at 77.47 184.15 0)
			(effects
				(font
					(size 1.27 1.27)
					(thickness 0.15)
				)
				(justify left bottom)
				(hide yes)
			)
		)
		(property "Description" ""
			(at 92.71 204.47 0)
			(effects
				(font
					(size 1.27 1.27)
				)
				(hide yes)
			)
		)
		(property "MPN" "CC0402MRX5R5BB106"
			(at 74.93 184.15 0)
			(effects
				(font
					(size 1.27 1.27)
					(thickness 0.15)
				)
				(justify left bottom)
				(hide yes)
			)
		)
		(property "Manufacturer" "YAGEO"
			(at 72.39 184.15 0)
			(effects
				(font
					(size 1.27 1.27)
					(thickness 0.15)
				)
				(justify left bottom)
				(hide yes)
			)
		)
		(property "License" "Apache-2.0"
			(at 69.85 184.15 0)
			(effects
				(font
					(size 1.27 1.27)
					(thickness 0.15)
				)
				(justify left bottom)
				(hide yes)
			)
		)
		(property "Author" "Antmicro"
			(at 67.31 184.15 0)
			(effects
				(font
					(size 1.27 1.27)
					(thickness 0.15)
				)
				(justify left bottom)
				(hide yes)
			)
		)
		(property "Val" "10u"
			(at 93.98 204.47 90)
			(effects
				(font
					(size 1.27 1.27)
					(thickness 0.15)
				)
				(justify left)
			)
		)
		(property "Voltage" ""
			(at 64.77 184.15 0)
			(effects
				(font
					(size 1.27 1.27)
				)
				(justify left bottom)
				(hide yes)
			)
		)
		(property "Dielectric" ""
			(at 62.23 184.15 0)
			(effects
				(font
					(size 1.27 1.27)
				)
				(justify left bottom)
				(hide yes)
			)
		)
		(pin "1"
		)
		(pin "2"
		)
		(instances
			(project "cm4-baseboard"
				(path ""
					(reference "C908")
					(unit 1)
				)
			)
			(project "usb"
				(path ""
					(reference "C908")
					(unit 1)
				)
			)
		)
	)
	(symbol
		(lib_id "antmicroTestPoints:TP_0.75mm_SMD")
		(at 161.29 265.43 0)
		(mirror x)
		(unit 1)
		(exclude_from_sim no)
		(in_bom no)
		(on_board yes)
		(dnp no)
		(property "Reference" "TP911"
			(at 165.1 265.43 0)
			(effects
				(font
					(size 1.27 1.27)
				)
				(justify left)
			)
		)
		(property "Value" "TP_0.75mm_SMD"
			(at 161.29 262.89 0)
			(effects
				(font
					(size 1.27 1.27)
					(thickness 0.15)
				)
				(justify left bottom)
				(hide yes)
			)
		)
		(property "Footprint" "antmicro-footprints:TP_SMD_0.75mm"
			(at 166.37 270.51 0)
			(effects
				(font
					(size 1.27 1.27)
					(thickness 0.15)
				)
				(justify left bottom)
				(hide yes)
			)
		)
		(property "Datasheet" ""
			(at 166.37 273.05 0)
			(effects
				(font
					(size 1.27 1.27)
					(thickness 0.15)
				)
				(justify left bottom)
				(hide yes)
			)
		)
		(property "Description" ""
			(at 161.29 265.43 0)
			(effects
				(font
					(size 1.27 1.27)
				)
				(hide yes)
			)
		)
		(property "MPN" ""
			(at 161.29 265.43 0)
			(effects
				(font
					(size 1.27 1.27)
					(thickness 0.15)
				)
				(justify left bottom)
				(hide yes)
			)
		)
		(property "Manufacturer" ""
			(at 161.29 265.43 0)
			(effects
				(font
					(size 1.27 1.27)
					(thickness 0.15)
				)
				(justify left bottom)
				(hide yes)
			)
		)
		(property "Author" "Antmicro"
			(at 176.53 250.19 0)
			(effects
				(font
					(size 1.27 1.27)
					(thickness 0.15)
				)
				(justify left bottom)
				(hide yes)
			)
		)
		(property "License" "Apache-2.0"
			(at 176.53 247.65 0)
			(effects
				(font
					(size 1.27 1.27)
					(thickness 0.15)
				)
				(justify left bottom)
				(hide yes)
			)
		)
		(pin "1"
		)
		(instances
			(project "cm4-baseboard"
				(path ""
					(reference "TP911")
					(unit 1)
				)
			)
			(project "usb"
				(path ""
					(reference "TP911")
					(unit 1)
				)
			)
		)
	)
	(symbol
		(lib_id "antmicropower:GND")
		(at 179.07 68.58 0)
		(unit 1)
		(exclude_from_sim no)
		(in_bom yes)
		(on_board yes)
		(dnp no)
		(fields_autoplaced yes)
		(property "Reference" "#PWR0921"
			(at 187.96 71.12 0)
			(effects
				(font
					(size 1.27 1.27)
					(thickness 0.15)
				)
				(justify left bottom)
				(hide yes)
			)
		)
		(property "Value" "GND"
			(at 177.0598 73.66 0)
			(effects
				(font
					(size 1.27 1.27)
					(thickness 0.15)
				)
				(justify left bottom)
			)
		)
		(property "Footprint" ""
			(at 187.96 76.2 0)
			(effects
				(font
					(size 1.27 1.27)
					(thickness 0.15)
				)
				(justify left bottom)
				(hide yes)
			)
		)
		(property "Datasheet" ""
			(at 187.96 81.28 0)
			(effects
				(font
					(size 1.27 1.27)
					(thickness 0.15)
				)
				(justify left bottom)
				(hide yes)
			)
		)
		(property "Description" ""
			(at 179.07 68.58 0)
			(effects
				(font
					(size 1.27 1.27)
				)
				(hide yes)
			)
		)
		(property "Author" "Antmicro"
			(at 187.96 76.2 0)
			(effects
				(font
					(size 1.27 1.27)
					(thickness 0.15)
				)
				(justify left bottom)
				(hide yes)
			)
		)
		(property "License" "Apache-2.0"
			(at 187.96 78.74 0)
			(effects
				(font
					(size 1.27 1.27)
					(thickness 0.15)
				)
				(justify left bottom)
				(hide yes)
			)
		)
		(pin "1"
		)
		(instances
			(project "cm4-baseboard"
				(path ""
					(reference "#PWR0921")
					(unit 1)
				)
			)
			(project "usb"
				(path ""
					(reference "#PWR0921")
					(unit 1)
				)
			)
		)
	)
	(symbol
		(lib_id "antmicroResistors0402:R_100k_0402")
		(at 198.12 186.69 270)
		(unit 1)
		(exclude_from_sim no)
		(in_bom yes)
		(on_board yes)
		(dnp no)
		(fields_autoplaced yes)
		(property "Reference" "R925"
			(at 200.66 187.96 90)
			(effects
				(font
					(size 1.27 1.27)
				)
				(justify left)
			)
		)
		(property "Value" "R_100k_0402"
			(at 194.31 186.69 0)
			(effects
				(font
					(size 1.27 1.27)
					(thickness 0.15)
				)
				(justify left bottom)
				(hide yes)
			)
		)
		(property "Footprint" "antmicro-footprints:R_0402_1005Metric"
			(at 203.2 191.77 0)
			(effects
				(font
					(size 1.27 1.27)
					(thickness 0.15)
				)
				(justify left bottom)
				(hide yes)
			)
		)
		(property "Datasheet" "https://www.bourns.com/docs/product-datasheets/cr.pdf"
			(at 198.12 186.69 0)
			(effects
				(font
					(size 1.27 1.27)
					(thickness 0.15)
				)
				(justify left bottom)
				(hide yes)
			)
		)
		(property "Description" ""
			(at 198.12 186.69 0)
			(effects
				(font
					(size 1.27 1.27)
				)
				(hide yes)
			)
		)
		(property "Manufacturer" "Bourns"
			(at 208.28 191.77 0)
			(effects
				(font
					(size 1.27 1.27)
					(thickness 0.15)
				)
				(justify left bottom)
				(hide yes)
			)
		)
		(property "MPN" "CR0402-FX-1003GLF"
			(at 205.74 191.77 0)
			(effects
				(font
					(size 1.27 1.27)
					(thickness 0.15)
				)
				(justify left bottom)
				(hide yes)
			)
		)
		(property "Val" "100k"
			(at 200.66 190.5 90)
			(effects
				(font
					(size 1.27 1.27)
					(thickness 0.15)
				)
				(justify left)
			)
		)
		(property "License" "Apache-2.0"
			(at 172.72 207.01 0)
			(effects
				(font
					(size 1.27 1.27)
					(thickness 0.15)
				)
				(justify left bottom)
				(hide yes)
			)
		)
		(property "Author" "Antmicro"
			(at 170.18 207.01 0)
			(effects
				(font
					(size 1.27 1.27)
					(thickness 0.15)
				)
				(justify left bottom)
				(hide yes)
			)
		)
		(property "Tolerance" "1%"
			(at 187.96 207.01 0)
			(effects
				(font
					(size 1.27 1.27)
				)
				(justify left bottom)
				(hide yes)
			)
		)
		(pin "1"
		)
		(pin "2"
		)
		(instances
			(project "cm4-baseboard"
				(path ""
					(reference "R925")
					(unit 1)
				)
			)
			(project "usb"
				(path ""
					(reference "R925")
					(unit 1)
				)
			)
		)
	)
	(symbol
		(lib_id "antmicropower:GND")
		(at 365.76 243.84 0)
		(unit 1)
		(exclude_from_sim no)
		(in_bom yes)
		(on_board yes)
		(dnp no)
		(property "Reference" "#PWR017"
			(at 374.65 246.38 0)
			(effects
				(font
					(size 1.27 1.27)
					(thickness 0.15)
				)
				(justify left bottom)
				(hide yes)
			)
		)
		(property "Value" "GND"
			(at 365.76 247.65 0)
			(effects
				(font
					(size 1.27 1.27)
					(thickness 0.15)
				)
			)
		)
		(property "Footprint" ""
			(at 374.65 251.46 0)
			(effects
				(font
					(size 1.27 1.27)
					(thickness 0.15)
				)
				(justify left bottom)
				(hide yes)
			)
		)
		(property "Datasheet" ""
			(at 374.65 256.54 0)
			(effects
				(font
					(size 1.27 1.27)
					(thickness 0.15)
				)
				(justify left bottom)
				(hide yes)
			)
		)
		(property "Description" ""
			(at 365.76 243.84 0)
			(effects
				(font
					(size 1.27 1.27)
				)
				(hide yes)
			)
		)
		(property "Author" "Antmicro"
			(at 374.65 251.46 0)
			(effects
				(font
					(size 1.27 1.27)
					(thickness 0.15)
				)
				(justify left bottom)
				(hide yes)
			)
		)
		(property "License" "Apache-2.0"
			(at 374.65 254 0)
			(effects
				(font
					(size 1.27 1.27)
					(thickness 0.15)
				)
				(justify left bottom)
				(hide yes)
			)
		)
		(pin "1"
		)
		(instances
			(project "cm4-baseboard"
				(path ""
					(reference "#PWR017")
					(unit 1)
				)
			)
		)
	)
	(symbol
		(lib_id "antmicroTestPoints:TP_0.75mm_SMD")
		(at 336.55 87.63 180)
		(unit 1)
		(exclude_from_sim no)
		(in_bom no)
		(on_board yes)
		(dnp no)
		(fields_autoplaced yes)
		(property "Reference" "TP914"
			(at 331.47 87.63 0)
			(effects
				(font
					(size 1.27 1.27)
				)
				(justify left)
			)
		)
		(property "Value" "TP_0.75mm_SMD"
			(at 336.55 85.09 0)
			(effects
				(font
					(size 1.27 1.27)
					(thickness 0.15)
				)
				(justify left bottom)
				(hide yes)
			)
		)
		(property "Footprint" "antmicro-footprints:TP_SMD_0.75mm"
			(at 331.47 92.71 0)
			(effects
				(font
					(size 1.27 1.27)
					(thickness 0.15)
				)
				(justify left bottom)
				(hide yes)
			)
		)
		(property "Datasheet" ""
			(at 331.47 95.25 0)
			(effects
				(font
					(size 1.27 1.27)
					(thickness 0.15)
				)
				(justify left bottom)
				(hide yes)
			)
		)
		(property "Description" ""
			(at 336.55 87.63 0)
			(effects
				(font
					(size 1.27 1.27)
				)
				(hide yes)
			)
		)
		(property "MPN" ""
			(at 336.55 87.63 0)
			(effects
				(font
					(size 1.27 1.27)
					(thickness 0.15)
				)
				(justify left bottom)
				(hide yes)
			)
		)
		(property "Manufacturer" ""
			(at 336.55 87.63 0)
			(effects
				(font
					(size 1.27 1.27)
					(thickness 0.15)
				)
				(justify left bottom)
				(hide yes)
			)
		)
		(property "Author" "Antmicro"
			(at 321.31 72.39 0)
			(effects
				(font
					(size 1.27 1.27)
					(thickness 0.15)
				)
				(justify left bottom)
				(hide yes)
			)
		)
		(property "License" "Apache-2.0"
			(at 321.31 69.85 0)
			(effects
				(font
					(size 1.27 1.27)
					(thickness 0.15)
				)
				(justify left bottom)
				(hide yes)
			)
		)
		(pin "1"
		)
		(instances
			(project "cm4-baseboard"
				(path ""
					(reference "TP914")
					(unit 1)
				)
			)
			(project "usb"
				(path ""
					(reference "TP914")
					(unit 1)
				)
			)
		)
	)
	(symbol
		(lib_id "antmicroResistors0402:R_1k_0402")
		(at 102.87 71.12 90)
		(unit 1)
		(exclude_from_sim no)
		(in_bom yes)
		(on_board yes)
		(dnp no)
		(property "Reference" "R902"
			(at 96.52 67.31 90)
			(effects
				(font
					(size 1.27 1.27)
					(thickness 0.15)
				)
				(justify right)
			)
		)
		(property "Value" "R_1k_0402"
			(at 115.57 50.8 0)
			(effects
				(font
					(size 1.27 1.27)
					(thickness 0.15)
				)
				(justify left bottom)
				(hide yes)
			)
		)
		(property "Footprint" "antmicro-footprints:R_0402_1005Metric"
			(at 118.11 50.8 0)
			(effects
				(font
					(size 1.27 1.27)
					(thickness 0.15)
				)
				(justify left bottom)
				(hide yes)
			)
		)
		(property "Datasheet" "https://www.bourns.com/docs/product-datasheets/cr.pdf"
			(at 120.65 50.8 0)
			(effects
				(font
					(size 1.27 1.27)
					(thickness 0.15)
				)
				(justify left bottom)
				(hide yes)
			)
		)
		(property "Description" ""
			(at 102.87 71.12 0)
			(effects
				(font
					(size 1.27 1.27)
				)
				(hide yes)
			)
		)
		(property "MPN" "CR0402-FX-1001GLF"
			(at 123.19 50.8 0)
			(effects
				(font
					(size 1.27 1.27)
					(thickness 0.15)
				)
				(justify left bottom)
				(hide yes)
			)
		)
		(property "Manufacturer" "Bourns"
			(at 125.73 50.8 0)
			(effects
				(font
					(size 1.27 1.27)
					(thickness 0.15)
				)
				(justify left bottom)
				(hide yes)
			)
		)
		(property "License" "Apache-2.0"
			(at 128.27 50.8 0)
			(effects
				(font
					(size 1.27 1.27)
					(thickness 0.15)
				)
				(justify left bottom)
				(hide yes)
			)
		)
		(property "Author" "Antmicro"
			(at 130.81 50.8 0)
			(effects
				(font
					(size 1.27 1.27)
					(thickness 0.15)
				)
				(justify left bottom)
				(hide yes)
			)
		)
		(property "Val" "1k"
			(at 99.06 69.85 90)
			(effects
				(font
					(size 1.27 1.27)
					(thickness 0.15)
				)
				(justify right)
			)
		)
		(property "Tolerance" "1%"
			(at 113.03 50.8 0)
			(effects
				(font
					(size 1.27 1.27)
				)
				(justify left bottom)
				(hide yes)
			)
		)
		(pin "1"
		)
		(pin "2"
		)
		(instances
			(project "cm4-baseboard"
				(path ""
					(reference "R902")
					(unit 1)
				)
			)
		)
	)
	(symbol
		(lib_id "antmicroCapacitors0402:C_100n_0402")
		(at 372.11 205.74 90)
		(unit 1)
		(exclude_from_sim no)
		(in_bom yes)
		(on_board yes)
		(dnp no)
		(property "Reference" "C934"
			(at 373.38 200.66 90)
			(effects
				(font
					(size 1.27 1.27)
					(thickness 0.15)
				)
				(justify right)
			)
		)
		(property "Value" "C_100n_0402"
			(at 382.27 185.42 0)
			(effects
				(font
					(size 1.27 1.27)
					(thickness 0.15)
				)
				(justify left bottom)
				(hide yes)
			)
		)
		(property "Footprint" "antmicro-footprints:C_0402_1005Metric"
			(at 384.81 185.42 0)
			(effects
				(font
					(size 1.27 1.27)
					(thickness 0.15)
				)
				(justify left bottom)
				(hide yes)
			)
		)
		(property "Datasheet" "https://www.murata.com/products/productdetail?partno=GRM155R61H104KE14%23"
			(at 387.35 185.42 0)
			(effects
				(font
					(size 1.27 1.27)
					(thickness 0.15)
				)
				(justify left bottom)
				(hide yes)
			)
		)
		(property "Description" ""
			(at 372.11 205.74 0)
			(effects
				(font
					(size 1.27 1.27)
				)
				(hide yes)
			)
		)
		(property "MPN" "GRM155R61H104KE14D"
			(at 389.89 185.42 0)
			(effects
				(font
					(size 1.27 1.27)
					(thickness 0.15)
				)
				(justify left bottom)
				(hide yes)
			)
		)
		(property "Manufacturer" "Murata"
			(at 392.43 185.42 0)
			(effects
				(font
					(size 1.27 1.27)
					(thickness 0.15)
				)
				(justify left bottom)
				(hide yes)
			)
		)
		(property "License" "Apache-2.0"
			(at 394.97 185.42 0)
			(effects
				(font
					(size 1.27 1.27)
					(thickness 0.15)
				)
				(justify left bottom)
				(hide yes)
			)
		)
		(property "Author" "Antmicro"
			(at 397.51 185.42 0)
			(effects
				(font
					(size 1.27 1.27)
					(thickness 0.15)
				)
				(justify left bottom)
				(hide yes)
			)
		)
		(property "Val" "100n"
			(at 373.38 205.74 90)
			(effects
				(font
					(size 1.27 1.27)
					(thickness 0.15)
				)
				(justify right)
			)
		)
		(property "Voltage" "50V"
			(at 400.05 185.42 0)
			(effects
				(font
					(size 1.27 1.27)
				)
				(justify left bottom)
				(hide yes)
			)
		)
		(property "Dielectric" "X5R"
			(at 402.59 185.42 0)
			(effects
				(font
					(size 1.27 1.27)
				)
				(justify left bottom)
				(hide yes)
			)
		)
		(pin "1"
		)
		(pin "2"
		)
		(instances
			(project "cm4-baseboard"
				(path ""
					(reference "C934")
					(unit 1)
				)
			)
		)
	)
	(symbol
		(lib_id "antmicropower:GND")
		(at 71.12 144.78 0)
		(unit 1)
		(exclude_from_sim no)
		(in_bom yes)
		(on_board yes)
		(dnp no)
		(fields_autoplaced yes)
		(property "Reference" "#PWR0924"
			(at 71.12 151.13 0)
			(effects
				(font
					(size 1.27 1.27)
				)
				(hide yes)
			)
		)
		(property "Value" "GND"
			(at 71.12 149.86 0)
			(effects
				(font
					(size 1.27 1.27)
				)
			)
		)
		(property "Footprint" ""
			(at 80.01 152.4 0)
			(effects
				(font
					(size 1.27 1.27)
					(thickness 0.15)
				)
				(justify left bottom)
				(hide yes)
			)
		)
		(property "Datasheet" ""
			(at 80.01 157.48 0)
			(effects
				(font
					(size 1.27 1.27)
					(thickness 0.15)
				)
				(justify left bottom)
				(hide yes)
			)
		)
		(property "Description" ""
			(at 71.12 144.78 0)
			(effects
				(font
					(size 1.27 1.27)
				)
				(hide yes)
			)
		)
		(property "Author" "Antmicro"
			(at 80.01 152.4 0)
			(effects
				(font
					(size 1.27 1.27)
					(thickness 0.15)
				)
				(justify left bottom)
				(hide yes)
			)
		)
		(property "License" "Apache-2.0"
			(at 80.01 154.94 0)
			(effects
				(font
					(size 1.27 1.27)
					(thickness 0.15)
				)
				(justify left bottom)
				(hide yes)
			)
		)
		(pin "1"
		)
		(instances
			(project "cm4-baseboard"
				(path ""
					(reference "#PWR0924")
					(unit 1)
				)
			)
			(project "usb"
				(path ""
					(reference "#PWR0924")
					(unit 1)
				)
			)
		)
	)
	(symbol
		(lib_id "antmicropower:+3V3")
		(at 365.76 215.9 0)
		(unit 1)
		(exclude_from_sim no)
		(in_bom yes)
		(on_board yes)
		(dnp no)
		(property "Reference" "#PWR012"
			(at 381 215.9 0)
			(effects
				(font
					(size 1.27 1.27)
					(thickness 0.15)
				)
				(justify left bottom)
				(hide yes)
			)
		)
		(property "Value" "+3V3"
			(at 365.76 212.09 0)
			(effects
				(font
					(size 1.27 1.27)
					(thickness 0.15)
				)
			)
		)
		(property "Footprint" ""
			(at 381 223.52 0)
			(effects
				(font
					(size 1.27 1.27)
					(thickness 0.15)
				)
				(justify left bottom)
				(hide yes)
			)
		)
		(property "Datasheet" ""
			(at 381 226.06 0)
			(effects
				(font
					(size 1.27 1.27)
					(thickness 0.15)
				)
				(justify left bottom)
				(hide yes)
			)
		)
		(property "Description" ""
			(at 365.76 215.9 0)
			(effects
				(font
					(size 1.27 1.27)
				)
				(hide yes)
			)
		)
		(property "Author" "Antmicro"
			(at 381 218.44 0)
			(effects
				(font
					(size 1.27 1.27)
					(thickness 0.15)
				)
				(justify left bottom)
				(hide yes)
			)
		)
		(property "License" "Apache-2.0"
			(at 381 220.98 0)
			(effects
				(font
					(size 1.27 1.27)
					(thickness 0.15)
				)
				(justify left bottom)
				(hide yes)
			)
		)
		(pin "1"
		)
		(instances
			(project "cm4-baseboard"
				(path ""
					(reference "#PWR012")
					(unit 1)
				)
			)
		)
	)
	(symbol
		(lib_id "antmicropower:GND")
		(at 300.99 156.21 0)
		(unit 1)
		(exclude_from_sim no)
		(in_bom yes)
		(on_board yes)
		(dnp no)
		(fields_autoplaced yes)
		(property "Reference" "#PWR0948"
			(at 300.99 162.56 0)
			(effects
				(font
					(size 1.27 1.27)
				)
				(hide yes)
			)
		)
		(property "Value" "GND"
			(at 300.99 161.29 0)
			(effects
				(font
					(size 1.27 1.27)
				)
			)
		)
		(property "Footprint" ""
			(at 309.88 163.83 0)
			(effects
				(font
					(size 1.27 1.27)
					(thickness 0.15)
				)
				(justify left bottom)
				(hide yes)
			)
		)
		(property "Datasheet" ""
			(at 309.88 168.91 0)
			(effects
				(font
					(size 1.27 1.27)
					(thickness 0.15)
				)
				(justify left bottom)
				(hide yes)
			)
		)
		(property "Description" ""
			(at 300.99 156.21 0)
			(effects
				(font
					(size 1.27 1.27)
				)
				(hide yes)
			)
		)
		(property "Author" "Antmicro"
			(at 309.88 163.83 0)
			(effects
				(font
					(size 1.27 1.27)
					(thickness 0.15)
				)
				(justify left bottom)
				(hide yes)
			)
		)
		(property "License" "Apache-2.0"
			(at 309.88 166.37 0)
			(effects
				(font
					(size 1.27 1.27)
					(thickness 0.15)
				)
				(justify left bottom)
				(hide yes)
			)
		)
		(pin "1"
		)
		(instances
			(project "cm4-baseboard"
				(path ""
					(reference "#PWR0948")
					(unit 1)
				)
			)
			(project "usb"
				(path ""
					(reference "#PWR0948")
					(unit 1)
				)
			)
		)
	)
	(symbol
		(lib_id "antmicropower:GND")
		(at 92.71 86.36 0)
		(unit 1)
		(exclude_from_sim no)
		(in_bom yes)
		(on_board yes)
		(dnp no)
		(property "Reference" "#PWR029"
			(at 101.6 88.9 0)
			(effects
				(font
					(size 1.27 1.27)
					(thickness 0.15)
				)
				(justify left bottom)
				(hide yes)
			)
		)
		(property "Value" "GND"
			(at 90.805 90.805 0)
			(effects
				(font
					(size 1.27 1.27)
					(thickness 0.15)
				)
				(justify left bottom)
			)
		)
		(property "Footprint" ""
			(at 101.6 93.98 0)
			(effects
				(font
					(size 1.27 1.27)
					(thickness 0.15)
				)
				(justify left bottom)
				(hide yes)
			)
		)
		(property "Datasheet" ""
			(at 101.6 99.06 0)
			(effects
				(font
					(size 1.27 1.27)
					(thickness 0.15)
				)
				(justify left bottom)
				(hide yes)
			)
		)
		(property "Description" ""
			(at 92.71 86.36 0)
			(effects
				(font
					(size 1.27 1.27)
				)
				(hide yes)
			)
		)
		(property "Author" "Antmicro"
			(at 101.6 93.98 0)
			(effects
				(font
					(size 1.27 1.27)
					(thickness 0.15)
				)
				(justify left bottom)
				(hide yes)
			)
		)
		(property "License" "Apache-2.0"
			(at 101.6 96.52 0)
			(effects
				(font
					(size 1.27 1.27)
					(thickness 0.15)
				)
				(justify left bottom)
				(hide yes)
			)
		)
		(pin "1"
		)
		(instances
			(project "cm4-baseboard"
				(path ""
					(reference "#PWR029")
					(unit 1)
				)
			)
		)
	)
	(symbol
		(lib_id "antmicroTestPoints:TP_0.75mm_SMD")
		(at 370.84 146.05 0)
		(mirror x)
		(unit 1)
		(exclude_from_sim no)
		(in_bom no)
		(on_board yes)
		(dnp no)
		(property "Reference" "TP916"
			(at 375.285 146.05 0)
			(effects
				(font
					(size 1.27 1.27)
				)
				(justify left)
			)
		)
		(property "Value" "TP_0.75mm_SMD"
			(at 370.84 143.51 0)
			(effects
				(font
					(size 1.27 1.27)
					(thickness 0.15)
				)
				(justify left bottom)
				(hide yes)
			)
		)
		(property "Footprint" "antmicro-footprints:TP_SMD_0.75mm"
			(at 375.92 151.13 0)
			(effects
				(font
					(size 1.27 1.27)
					(thickness 0.15)
				)
				(justify left bottom)
				(hide yes)
			)
		)
		(property "Datasheet" ""
			(at 375.92 153.67 0)
			(effects
				(font
					(size 1.27 1.27)
					(thickness 0.15)
				)
				(justify left bottom)
				(hide yes)
			)
		)
		(property "Description" ""
			(at 370.84 146.05 0)
			(effects
				(font
					(size 1.27 1.27)
				)
				(hide yes)
			)
		)
		(property "MPN" ""
			(at 370.84 146.05 0)
			(effects
				(font
					(size 1.27 1.27)
					(thickness 0.15)
				)
				(justify left bottom)
				(hide yes)
			)
		)
		(property "Manufacturer" ""
			(at 370.84 146.05 0)
			(effects
				(font
					(size 1.27 1.27)
					(thickness 0.15)
				)
				(justify left bottom)
				(hide yes)
			)
		)
		(property "Author" "Antmicro"
			(at 386.08 130.81 0)
			(effects
				(font
					(size 1.27 1.27)
					(thickness 0.15)
				)
				(justify left bottom)
				(hide yes)
			)
		)
		(property "License" "Apache-2.0"
			(at 386.08 128.27 0)
			(effects
				(font
					(size 1.27 1.27)
					(thickness 0.15)
				)
				(justify left bottom)
				(hide yes)
			)
		)
		(pin "1"
		)
		(instances
			(project "cm4-baseboard"
				(path ""
					(reference "TP916")
					(unit 1)
				)
			)
			(project "usb"
				(path ""
					(reference "TP916")
					(unit 1)
				)
			)
		)
	)
	(symbol
		(lib_id "antmicroCommonModeChokes:Choke_DLW21SN900SQ2L")
		(at 49.53 72.39 0)
		(unit 1)
		(exclude_from_sim no)
		(in_bom yes)
		(on_board yes)
		(dnp no)
		(property "Reference" "T902"
			(at 54.61 66.04 0)
			(effects
				(font
					(size 1.27 1.27)
					(thickness 0.15)
				)
			)
		)
		(property "Value" "Choke_DLW21SN900SQ2L"
			(at 64.77 82.55 0)
			(effects
				(font
					(size 1.27 1.27)
					(thickness 0.15)
				)
				(justify left bottom)
				(hide yes)
			)
		)
		(property "Footprint" "antmicro-footprints:Choke_Murata-DLW21"
			(at 64.77 85.09 0)
			(effects
				(font
					(size 1.27 1.27)
					(thickness 0.15)
				)
				(justify left bottom)
				(hide yes)
			)
		)
		(property "Datasheet" "https://www.murata.com/en-us/products/productdetail?partno=DLW21SN900SQ2%23"
			(at 64.77 87.63 0)
			(effects
				(font
					(size 1.27 1.27)
					(thickness 0.15)
				)
				(justify left bottom)
				(hide yes)
			)
		)
		(property "Description" ""
			(at 49.53 72.39 0)
			(effects
				(font
					(size 1.27 1.27)
				)
				(hide yes)
			)
		)
		(property "Manufacturer" "Murata"
			(at 64.77 90.17 0)
			(effects
				(font
					(size 1.27 1.27)
					(thickness 0.15)
				)
				(justify left bottom)
				(hide yes)
			)
		)
		(property "MPN" "DLW21SN900SQ2L"
			(at 54.61 68.58 0)
			(effects
				(font
					(size 1.27 1.27)
					(thickness 0.15)
				)
			)
		)
		(property "IMax" "0.33 A"
			(at 64.77 92.71 0)
			(effects
				(font
					(size 1.27 1.27)
					(thickness 0.15)
				)
				(justify left bottom)
				(hide yes)
			)
		)
		(property "Author" "Antmicro"
			(at 64.77 95.25 0)
			(effects
				(font
					(size 1.27 1.27)
					(thickness 0.15)
				)
				(justify left bottom)
				(hide yes)
			)
		)
		(property "License" "Apache-2.0"
			(at 64.77 97.79 0)
			(effects
				(font
					(size 1.27 1.27)
					(thickness 0.15)
				)
				(justify left bottom)
				(hide yes)
			)
		)
		(pin "4"
		)
		(pin "1"
		)
		(pin "2"
		)
		(pin "3"
		)
		(instances
			(project "cm4-baseboard"
				(path ""
					(reference "T902")
					(unit 1)
				)
			)
			(project "usb"
				(path ""
					(reference "T902")
					(unit 1)
				)
			)
		)
	)
	(symbol
		(lib_id "antmicropower:GND")
		(at 368.3 223.52 0)
		(unit 1)
		(exclude_from_sim no)
		(in_bom yes)
		(on_board yes)
		(dnp no)
		(property "Reference" "#PWR0925"
			(at 377.19 226.06 0)
			(effects
				(font
					(size 1.27 1.27)
					(thickness 0.15)
				)
				(justify left bottom)
				(hide yes)
			)
		)
		(property "Value" "GND"
			(at 368.3 227.33 0)
			(effects
				(font
					(size 1.27 1.27)
					(thickness 0.15)
				)
			)
		)
		(property "Footprint" ""
			(at 377.19 231.14 0)
			(effects
				(font
					(size 1.27 1.27)
					(thickness 0.15)
				)
				(justify left bottom)
				(hide yes)
			)
		)
		(property "Datasheet" ""
			(at 377.19 236.22 0)
			(effects
				(font
					(size 1.27 1.27)
					(thickness 0.15)
				)
				(justify left bottom)
				(hide yes)
			)
		)
		(property "Description" ""
			(at 368.3 223.52 0)
			(effects
				(font
					(size 1.27 1.27)
				)
				(hide yes)
			)
		)
		(property "Author" "Antmicro"
			(at 377.19 231.14 0)
			(effects
				(font
					(size 1.27 1.27)
					(thickness 0.15)
				)
				(justify left bottom)
				(hide yes)
			)
		)
		(property "License" "Apache-2.0"
			(at 377.19 233.68 0)
			(effects
				(font
					(size 1.27 1.27)
					(thickness 0.15)
				)
				(justify left bottom)
				(hide yes)
			)
		)
		(pin "1"
		)
		(instances
			(project "cm4-baseboard"
				(path ""
					(reference "#PWR0925")
					(unit 1)
				)
			)
		)
	)
	(symbol
		(lib_id "antmicroTVSDiodes:PUSB3F96X_PASS")
		(at 64.77 232.41 0)
		(unit 1)
		(exclude_from_sim no)
		(in_bom yes)
		(on_board yes)
		(dnp no)
		(fields_autoplaced yes)
		(property "Reference" "D901"
			(at 78.74 234.9499 0)
			(effects
				(font
					(size 1.27 1.27)
					(thickness 0.15)
				)
				(justify left)
			)
		)
		(property "Value" "PUSB3F96X_PASS"
			(at 90.17 240.03 0)
			(effects
				(font
					(size 1.27 1.27)
					(thickness 0.15)
				)
				(justify left bottom)
				(hide yes)
			)
		)
		(property "Footprint" "antmicro-footprints:Nexperia_DFN-10_2.5x1mm_P0.5mm"
			(at 90.17 242.57 0)
			(effects
				(font
					(size 1.27 1.27)
					(thickness 0.15)
				)
				(justify left bottom)
				(hide yes)
			)
		)
		(property "Datasheet" "https://mouser.com/datasheet/2/916/PUSB3F96-1600324.pdf"
			(at 90.17 245.11 0)
			(effects
				(font
					(size 1.27 1.27)
					(thickness 0.15)
				)
				(justify left bottom)
				(hide yes)
			)
		)
		(property "Description" ""
			(at 64.77 232.41 0)
			(effects
				(font
					(size 1.27 1.27)
				)
				(hide yes)
			)
		)
		(property "Manufacturer" "Nexperia"
			(at 90.17 247.65 0)
			(effects
				(font
					(size 1.27 1.27)
					(thickness 0.15)
				)
				(justify left bottom)
				(hide yes)
			)
		)
		(property "MPN" "PUSB3F96X"
			(at 78.74 237.4899 0)
			(effects
				(font
					(size 1.27 1.27)
					(thickness 0.15)
				)
				(justify left)
			)
		)
		(property "Author" "Antmicro"
			(at 90.17 250.19 0)
			(effects
				(font
					(size 1.27 1.27)
					(thickness 0.15)
				)
				(justify left bottom)
				(hide yes)
			)
		)
		(property "License" "Apache-2.0"
			(at 90.17 252.73 0)
			(effects
				(font
					(size 1.27 1.27)
					(thickness 0.15)
				)
				(justify left bottom)
				(hide yes)
			)
		)
		(pin "1"
		)
		(pin "10"
		)
		(pin "2"
		)
		(pin "3"
		)
		(pin "4"
		)
		(pin "5"
		)
		(pin "6"
		)
		(pin "7"
		)
		(pin "8"
		)
		(pin "9"
		)
		(instances
			(project "cm4-baseboard"
				(path ""
					(reference "D901")
					(unit 1)
				)
			)
			(project "usb"
				(path ""
					(reference "D901")
					(unit 1)
				)
			)
		)
	)
	(symbol
		(lib_id "antmicroResistors0402:R_0R_0402")
		(at 313.69 171.45 90)
		(unit 1)
		(exclude_from_sim no)
		(in_bom yes)
		(on_board yes)
		(dnp no)
		(property "Reference" "R931"
			(at 314.96 167.64 90)
			(effects
				(font
					(size 1.27 1.27)
				)
				(justify right)
			)
		)
		(property "Value" "R_0R_0402"
			(at 317.5 171.45 0)
			(effects
				(font
					(size 1.27 1.27)
				)
				(justify left bottom)
				(hide yes)
			)
		)
		(property "Footprint" "antmicro-footprints:R_0402_1005Metric"
			(at 308.61 166.37 0)
			(effects
				(font
					(size 1.524 1.524)
				)
				(justify left bottom)
				(hide yes)
			)
		)
		(property "Datasheet" "https://industrial.panasonic.com/cdbs/www-data/pdf/RDA0000/AOA0000C301.pdf"
			(at 313.69 171.45 0)
			(effects
				(font
					(size 1.27 1.27)
				)
				(justify left bottom)
				(hide yes)
			)
		)
		(property "Description" ""
			(at 313.69 171.45 0)
			(effects
				(font
					(size 1.27 1.27)
				)
				(hide yes)
			)
		)
		(property "Manufacturer" "Panasonic"
			(at 303.53 166.37 0)
			(effects
				(font
					(size 1.524 1.524)
				)
				(justify left bottom)
				(hide yes)
			)
		)
		(property "MPN" "ERJ2GE0R00X"
			(at 306.07 166.37 0)
			(effects
				(font
					(size 1.524 1.524)
				)
				(justify left bottom)
				(hide yes)
			)
		)
		(property "Val" "0R"
			(at 314.96 170.18 90)
			(effects
				(font
					(size 1.27 1.27)
				)
				(justify right)
			)
		)
		(property "License" "Apache-2.0"
			(at 339.09 151.13 0)
			(effects
				(font
					(size 1.27 1.27)
					(thickness 0.15)
				)
				(justify left bottom)
				(hide yes)
			)
		)
		(property "Author" "Antmicro"
			(at 341.63 151.13 0)
			(effects
				(font
					(size 1.27 1.27)
					(thickness 0.15)
				)
				(justify left bottom)
				(hide yes)
			)
		)
		(property "Tolerance" "~"
			(at 323.85 151.13 0)
			(effects
				(font
					(size 1.27 1.27)
				)
				(justify left bottom)
				(hide yes)
			)
		)
		(property "Current" "1A"
			(at 311.785 168.91 0)
			(effects
				(font
					(size 1.27 1.27)
					(thickness 0.15)
				)
				(hide yes)
			)
		)
		(pin "1"
		)
		(pin "2"
		)
		(instances
			(project "cm4-baseboard"
				(path ""
					(reference "R931")
					(unit 1)
				)
			)
		)
	)
	(symbol
		(lib_id "antmicroCapacitors0402:C_100n_0402")
		(at 384.81 168.91 90)
		(unit 1)
		(exclude_from_sim no)
		(in_bom yes)
		(on_board yes)
		(dnp no)
		(property "Reference" "C935"
			(at 386.08 163.83 90)
			(effects
				(font
					(size 1.27 1.27)
					(thickness 0.15)
				)
				(justify right)
			)
		)
		(property "Value" "C_100n_0402"
			(at 394.97 148.59 0)
			(effects
				(font
					(size 1.27 1.27)
					(thickness 0.15)
				)
				(justify left bottom)
				(hide yes)
			)
		)
		(property "Footprint" "antmicro-footprints:C_0402_1005Metric"
			(at 397.51 148.59 0)
			(effects
				(font
					(size 1.27 1.27)
					(thickness 0.15)
				)
				(justify left bottom)
				(hide yes)
			)
		)
		(property "Datasheet" "https://www.murata.com/products/productdetail?partno=GRM155R61H104KE14%23"
			(at 400.05 148.59 0)
			(effects
				(font
					(size 1.27 1.27)
					(thickness 0.15)
				)
				(justify left bottom)
				(hide yes)
			)
		)
		(property "Description" ""
			(at 384.81 168.91 0)
			(effects
				(font
					(size 1.27 1.27)
				)
				(hide yes)
			)
		)
		(property "MPN" "GRM155R61H104KE14D"
			(at 402.59 148.59 0)
			(effects
				(font
					(size 1.27 1.27)
					(thickness 0.15)
				)
				(justify left bottom)
				(hide yes)
			)
		)
		(property "Manufacturer" "Murata"
			(at 405.13 148.59 0)
			(effects
				(font
					(size 1.27 1.27)
					(thickness 0.15)
				)
				(justify left bottom)
				(hide yes)
			)
		)
		(property "License" "Apache-2.0"
			(at 407.67 148.59 0)
			(effects
				(font
					(size 1.27 1.27)
					(thickness 0.15)
				)
				(justify left bottom)
				(hide yes)
			)
		)
		(property "Author" "Antmicro"
			(at 410.21 148.59 0)
			(effects
				(font
					(size 1.27 1.27)
					(thickness 0.15)
				)
				(justify left bottom)
				(hide yes)
			)
		)
		(property "Val" "100n"
			(at 386.08 168.91 90)
			(effects
				(font
					(size 1.27 1.27)
					(thickness 0.15)
				)
				(justify right)
			)
		)
		(property "Voltage" "50V"
			(at 412.75 148.59 0)
			(effects
				(font
					(size 1.27 1.27)
				)
				(justify left bottom)
				(hide yes)
			)
		)
		(property "Dielectric" "X5R"
			(at 415.29 148.59 0)
			(effects
				(font
					(size 1.27 1.27)
				)
				(justify left bottom)
				(hide yes)
			)
		)
		(pin "1"
		)
		(pin "2"
		)
		(instances
			(project "cm4-baseboard"
				(path ""
					(reference "C935")
					(unit 1)
				)
			)
		)
	)
	(symbol
		(lib_id "antmicropower:+3V3")
		(at 384.81 199.39 0)
		(unit 1)
		(exclude_from_sim no)
		(in_bom yes)
		(on_board yes)
		(dnp no)
		(fields_autoplaced yes)
		(property "Reference" "#PWR021"
			(at 400.05 201.93 0)
			(effects
				(font
					(size 1.27 1.27)
					(thickness 0.15)
				)
				(justify left bottom)
				(hide yes)
			)
		)
		(property "Value" "+3V3"
			(at 384.175 195.58 0)
			(effects
				(font
					(size 1.27 1.27)
					(thickness 0.15)
				)
			)
		)
		(property "Footprint" ""
			(at 400.05 207.01 0)
			(effects
				(font
					(size 1.27 1.27)
					(thickness 0.15)
				)
				(justify left bottom)
				(hide yes)
			)
		)
		(property "Datasheet" ""
			(at 400.05 209.55 0)
			(effects
				(font
					(size 1.27 1.27)
					(thickness 0.15)
				)
				(justify left bottom)
				(hide yes)
			)
		)
		(property "Description" ""
			(at 384.81 199.39 0)
			(effects
				(font
					(size 1.27 1.27)
				)
				(hide yes)
			)
		)
		(property "Author" "Antmicro"
			(at 400.05 207.01 0)
			(effects
				(font
					(size 1.27 1.27)
					(thickness 0.15)
				)
				(justify left bottom)
				(hide yes)
			)
		)
		(property "License" "Apache-2.0"
			(at 400.05 209.55 0)
			(effects
				(font
					(size 1.27 1.27)
					(thickness 0.15)
				)
				(justify left bottom)
				(hide yes)
			)
		)
		(pin "1"
		)
		(instances
			(project "cm4-baseboard"
				(path ""
					(reference "#PWR021")
					(unit 1)
				)
			)
		)
	)
	(symbol
		(lib_id "antmicropower:GND")
		(at 71.12 66.04 0)
		(mirror y)
		(unit 1)
		(exclude_from_sim no)
		(in_bom yes)
		(on_board yes)
		(dnp no)
		(fields_autoplaced yes)
		(property "Reference" "#PWR0906"
			(at 62.23 68.58 0)
			(effects
				(font
					(size 1.27 1.27)
					(thickness 0.15)
				)
				(justify left bottom)
				(hide yes)
			)
		)
		(property "Value" "GND"
			(at 73.1302 71.12 0)
			(effects
				(font
					(size 1.27 1.27)
					(thickness 0.15)
				)
				(justify left bottom)
			)
		)
		(property "Footprint" ""
			(at 62.23 73.66 0)
			(effects
				(font
					(size 1.27 1.27)
					(thickness 0.15)
				)
				(justify left bottom)
				(hide yes)
			)
		)
		(property "Datasheet" ""
			(at 62.23 78.74 0)
			(effects
				(font
					(size 1.27 1.27)
					(thickness 0.15)
				)
				(justify left bottom)
				(hide yes)
			)
		)
		(property "Description" ""
			(at 71.12 66.04 0)
			(effects
				(font
					(size 1.27 1.27)
				)
				(hide yes)
			)
		)
		(property "Author" "Antmicro"
			(at 62.23 73.66 0)
			(effects
				(font
					(size 1.27 1.27)
					(thickness 0.15)
				)
				(justify left bottom)
				(hide yes)
			)
		)
		(property "License" "Apache-2.0"
			(at 62.23 76.2 0)
			(effects
				(font
					(size 1.27 1.27)
					(thickness 0.15)
				)
				(justify left bottom)
				(hide yes)
			)
		)
		(pin "1"
		)
		(instances
			(project "cm4-baseboard"
				(path ""
					(reference "#PWR0906")
					(unit 1)
				)
			)
			(project "usb"
				(path ""
					(reference "#PWR0906")
					(unit 1)
				)
			)
		)
	)
	(symbol
		(lib_id "antmicropower:GND")
		(at 77.47 144.78 0)
		(unit 1)
		(exclude_from_sim no)
		(in_bom yes)
		(on_board yes)
		(dnp no)
		(fields_autoplaced yes)
		(property "Reference" "#PWR0930"
			(at 77.47 151.13 0)
			(effects
				(font
					(size 1.27 1.27)
				)
				(hide yes)
			)
		)
		(property "Value" "GND"
			(at 77.47 149.86 0)
			(effects
				(font
					(size 1.27 1.27)
				)
			)
		)
		(property "Footprint" ""
			(at 86.36 152.4 0)
			(effects
				(font
					(size 1.27 1.27)
					(thickness 0.15)
				)
				(justify left bottom)
				(hide yes)
			)
		)
		(property "Datasheet" ""
			(at 86.36 157.48 0)
			(effects
				(font
					(size 1.27 1.27)
					(thickness 0.15)
				)
				(justify left bottom)
				(hide yes)
			)
		)
		(property "Description" ""
			(at 77.47 144.78 0)
			(effects
				(font
					(size 1.27 1.27)
				)
				(hide yes)
			)
		)
		(property "Author" "Antmicro"
			(at 86.36 152.4 0)
			(effects
				(font
					(size 1.27 1.27)
					(thickness 0.15)
				)
				(justify left bottom)
				(hide yes)
			)
		)
		(property "License" "Apache-2.0"
			(at 86.36 154.94 0)
			(effects
				(font
					(size 1.27 1.27)
					(thickness 0.15)
				)
				(justify left bottom)
				(hide yes)
			)
		)
		(pin "1"
		)
		(instances
			(project "cm4-baseboard"
				(path ""
					(reference "#PWR0930")
					(unit 1)
				)
			)
			(project "usb"
				(path ""
					(reference "#PWR0930")
					(unit 1)
				)
			)
		)
	)
	(symbol
		(lib_id "antmicroInterfaceControllers:TUSB321RWBR")
		(at 129.54 252.73 0)
		(unit 1)
		(exclude_from_sim no)
		(in_bom yes)
		(on_board yes)
		(dnp no)
		(fields_autoplaced yes)
		(property "Reference" "U906"
			(at 144.78 245.11 0)
			(effects
				(font
					(size 1.27 1.27)
					(thickness 0.15)
				)
			)
		)
		(property "Value" "TUSB321RWBR"
			(at 144.78 247.65 0)
			(effects
				(font
					(size 1.27 1.27)
					(thickness 0.15)
				)
				(hide yes)
			)
		)
		(property "Footprint" "antmicro-footprints:Texas_X2QFN-12_1.6x1.6mm_P0.4mm"
			(at 175.26 260.35 0)
			(effects
				(font
					(size 1.27 1.27)
					(thickness 0.15)
				)
				(justify left bottom)
				(hide yes)
			)
		)
		(property "Datasheet" "https://www.ti.com/lit/ds/symlink/tusb321.pdf?ts=1709901243739"
			(at 175.26 262.89 0)
			(effects
				(font
					(size 1.27 1.27)
					(thickness 0.15)
				)
				(justify left bottom)
				(hide yes)
			)
		)
		(property "Description" ""
			(at 129.54 252.73 0)
			(effects
				(font
					(size 1.27 1.27)
				)
				(hide yes)
			)
		)
		(property "MPN" "TUSB321RWBR"
			(at 144.78 247.65 0)
			(effects
				(font
					(size 1.27 1.27)
					(thickness 0.15)
				)
			)
		)
		(property "Manufacturer" "Texas Instruments"
			(at 175.26 267.97 0)
			(effects
				(font
					(size 1.27 1.27)
					(thickness 0.15)
				)
				(justify left bottom)
				(hide yes)
			)
		)
		(property "Author" "Antmicro"
			(at 175.26 270.51 0)
			(effects
				(font
					(size 1.27 1.27)
					(thickness 0.15)
				)
				(justify left bottom)
				(hide yes)
			)
		)
		(property "License" "Apache-2.0"
			(at 175.26 273.05 0)
			(effects
				(font
					(size 1.27 1.27)
					(thickness 0.15)
				)
				(justify left bottom)
				(hide yes)
			)
		)
		(pin "5"
		)
		(pin "9"
		)
		(pin "8"
		)
		(pin "6"
		)
		(pin "11"
		)
		(pin "7"
		)
		(pin "4"
		)
		(pin "12"
		)
		(pin "2"
		)
		(pin "3"
		)
		(pin "10"
		)
		(pin "1"
		)
		(instances
			(project "cm4-baseboard"
				(path ""
					(reference "U906")
					(unit 1)
				)
			)
			(project "usb"
				(path ""
					(reference "U906")
					(unit 1)
				)
			)
		)
	)
	(symbol
		(lib_id "antmicroTVSDiodes:PUSB3F96X_PASS")
		(at 67.31 31.75 0)
		(unit 1)
		(exclude_from_sim no)
		(in_bom yes)
		(on_board yes)
		(dnp no)
		(fields_autoplaced yes)
		(property "Reference" "D902"
			(at 81.28 34.2899 0)
			(effects
				(font
					(size 1.27 1.27)
					(thickness 0.15)
				)
				(justify left)
			)
		)
		(property "Value" "PUSB3F96X_PASS"
			(at 92.71 39.37 0)
			(effects
				(font
					(size 1.27 1.27)
					(thickness 0.15)
				)
				(justify left bottom)
				(hide yes)
			)
		)
		(property "Footprint" "antmicro-footprints:Nexperia_DFN-10_2.5x1mm_P0.5mm"
			(at 92.71 41.91 0)
			(effects
				(font
					(size 1.27 1.27)
					(thickness 0.15)
				)
				(justify left bottom)
				(hide yes)
			)
		)
		(property "Datasheet" "https://mouser.com/datasheet/2/916/PUSB3F96-1600324.pdf"
			(at 92.71 44.45 0)
			(effects
				(font
					(size 1.27 1.27)
					(thickness 0.15)
				)
				(justify left bottom)
				(hide yes)
			)
		)
		(property "Description" ""
			(at 67.31 31.75 0)
			(effects
				(font
					(size 1.27 1.27)
				)
				(hide yes)
			)
		)
		(property "Manufacturer" "Nexperia"
			(at 92.71 46.99 0)
			(effects
				(font
					(size 1.27 1.27)
					(thickness 0.15)
				)
				(justify left bottom)
				(hide yes)
			)
		)
		(property "MPN" "PUSB3F96X"
			(at 81.28 36.8299 0)
			(effects
				(font
					(size 1.27 1.27)
					(thickness 0.15)
				)
				(justify left)
			)
		)
		(property "Author" "Antmicro"
			(at 92.71 49.53 0)
			(effects
				(font
					(size 1.27 1.27)
					(thickness 0.15)
				)
				(justify left bottom)
				(hide yes)
			)
		)
		(property "License" "Apache-2.0"
			(at 92.71 52.07 0)
			(effects
				(font
					(size 1.27 1.27)
					(thickness 0.15)
				)
				(justify left bottom)
				(hide yes)
			)
		)
		(pin "1"
		)
		(pin "10"
		)
		(pin "2"
		)
		(pin "3"
		)
		(pin "4"
		)
		(pin "5"
		)
		(pin "6"
		)
		(pin "7"
		)
		(pin "8"
		)
		(pin "9"
		)
		(instances
			(project "cm4-baseboard"
				(path ""
					(reference "D902")
					(unit 1)
				)
			)
			(project "usb"
				(path ""
					(reference "D902")
					(unit 1)
				)
			)
		)
	)
	(symbol
		(lib_id "antmicroUSBConnectors:USB-C_GCT_USB4105-GF-A")
		(at 38.1 196.85 0)
		(unit 1)
		(exclude_from_sim no)
		(in_bom yes)
		(on_board yes)
		(dnp no)
		(property "Reference" "J901"
			(at 24.13 189.23 0)
			(effects
				(font
					(size 1.27 1.27)
					(thickness 0.15)
				)
			)
		)
		(property "Value" "USB-C_GCT_USB4105-GF-A"
			(at 24.765 191.77 0)
			(effects
				(font
					(size 1.27 1.27)
					(thickness 0.15)
				)
				(hide yes)
			)
		)
		(property "Footprint" "antmicro-footprints:USB-C_Receptacle_GCT_USB4105-GF-A"
			(at 76.2 204.47 0)
			(effects
				(font
					(size 1.27 1.27)
					(thickness 0.15)
				)
				(justify left bottom)
				(hide yes)
			)
		)
		(property "Datasheet" "https://gct.co/files/drawings/usb4105.pdf"
			(at 76.2 207.01 0)
			(effects
				(font
					(size 1.27 1.27)
					(thickness 0.15)
				)
				(justify left bottom)
				(hide yes)
			)
		)
		(property "Description" ""
			(at 38.1 196.85 0)
			(effects
				(font
					(size 1.27 1.27)
				)
				(hide yes)
			)
		)
		(property "Manufacturer" "GCT"
			(at 76.2 209.55 0)
			(effects
				(font
					(size 1.27 1.27)
					(thickness 0.15)
				)
				(justify left bottom)
				(hide yes)
			)
		)
		(property "MPN" "USB4105-GF-A"
			(at 24.13 191.77 0)
			(effects
				(font
					(size 1.27 1.27)
					(thickness 0.15)
				)
			)
		)
		(property "Author" "Antmicro"
			(at 76.2 214.63 0)
			(effects
				(font
					(size 1.27 1.27)
					(thickness 0.15)
				)
				(justify left bottom)
				(hide yes)
			)
		)
		(property "License" "Apache-2.0"
			(at 76.2 217.17 0)
			(effects
				(font
					(size 1.27 1.27)
					(thickness 0.15)
				)
				(justify left bottom)
				(hide yes)
			)
		)
		(pin "A1"
		)
		(pin "A12"
		)
		(pin "A4"
		)
		(pin "A5"
		)
		(pin "A6"
		)
		(pin "A7"
		)
		(pin "A8"
		)
		(pin "A9"
		)
		(pin "B1"
		)
		(pin "B12"
		)
		(pin "B4"
		)
		(pin "B5"
		)
		(pin "B6"
		)
		(pin "B7"
		)
		(pin "B8"
		)
		(pin "B9"
		)
		(pin "SH"
		)
		(instances
			(project "cm4-baseboard"
				(path ""
					(reference "J901")
					(unit 1)
				)
			)
			(project "usb"
				(path ""
					(reference "J901")
					(unit 1)
				)
			)
		)
	)
	(symbol
		(lib_id "antmicroTestPoints:TP_0.75mm_SMD")
		(at 335.28 116.84 90)
		(unit 1)
		(exclude_from_sim no)
		(in_bom no)
		(on_board yes)
		(dnp no)
		(property "Reference" "TP906"
			(at 334.01 111.76 90)
			(effects
				(font
					(size 1.27 1.27)
				)
				(justify right)
			)
		)
		(property "Value" "TP_0.75mm_SMD"
			(at 337.82 116.84 0)
			(effects
				(font
					(size 1.27 1.27)
					(thickness 0.15)
				)
				(justify left bottom)
				(hide yes)
			)
		)
		(property "Footprint" "antmicro-footprints:TP_SMD_0.75mm"
			(at 330.2 111.76 0)
			(effects
				(font
					(size 1.27 1.27)
					(thickness 0.15)
				)
				(justify left bottom)
				(hide yes)
			)
		)
		(property "Datasheet" ""
			(at 327.66 111.76 0)
			(effects
				(font
					(size 1.27 1.27)
					(thickness 0.15)
				)
				(justify left bottom)
				(hide yes)
			)
		)
		(property "Description" ""
			(at 335.28 116.84 0)
			(effects
				(font
					(size 1.27 1.27)
				)
				(hide yes)
			)
		)
		(property "MPN" ""
			(at 335.28 116.84 0)
			(effects
				(font
					(size 1.27 1.27)
					(thickness 0.15)
				)
				(justify left bottom)
				(hide yes)
			)
		)
		(property "Manufacturer" ""
			(at 335.28 116.84 0)
			(effects
				(font
					(size 1.27 1.27)
					(thickness 0.15)
				)
				(justify left bottom)
				(hide yes)
			)
		)
		(property "Author" "Antmicro"
			(at 350.52 101.6 0)
			(effects
				(font
					(size 1.27 1.27)
					(thickness 0.15)
				)
				(justify left bottom)
				(hide yes)
			)
		)
		(property "License" "Apache-2.0"
			(at 353.06 101.6 0)
			(effects
				(font
					(size 1.27 1.27)
					(thickness 0.15)
				)
				(justify left bottom)
				(hide yes)
			)
		)
		(pin "1"
		)
		(instances
			(project "cm4-baseboard"
				(path ""
					(reference "TP906")
					(unit 1)
				)
			)
			(project "usb"
				(path ""
					(reference "TP906")
					(unit 1)
				)
			)
		)
	)
	(symbol
		(lib_id "antmicroInterfaceControllers:FT4233HPQ")
		(at 337.82 49.53 0)
		(unit 1)
		(exclude_from_sim no)
		(in_bom yes)
		(on_board yes)
		(dnp no)
		(fields_autoplaced yes)
		(property "Reference" "U905"
			(at 353.695 41.91 0)
			(effects
				(font
					(size 1.27 1.27)
					(thickness 0.15)
				)
			)
		)
		(property "Value" "FT4233HPQ"
			(at 383.54 57.15 0)
			(effects
				(font
					(size 1.27 1.27)
					(thickness 0.15)
				)
				(justify left bottom)
				(hide yes)
			)
		)
		(property "Footprint" "antmicro-footprints:QFN-76-1EP_9x9mm_P0.4mm_EP6.3x6.3mm"
			(at 383.54 59.69 0)
			(effects
				(font
					(size 1.27 1.27)
					(thickness 0.15)
				)
				(justify left bottom)
				(hide yes)
			)
		)
		(property "Datasheet" "https://ftdichip.com/wp-content/uploads/2023/09/DS_FT4233HP-v1.5.pdf"
			(at 383.54 62.23 0)
			(effects
				(font
					(size 1.27 1.27)
					(thickness 0.15)
				)
				(justify left bottom)
				(hide yes)
			)
		)
		(property "Description" ""
			(at 337.82 49.53 0)
			(effects
				(font
					(size 1.27 1.27)
				)
				(hide yes)
			)
		)
		(property "MPN" "FT4233HPQ-REEL"
			(at 353.695 44.45 0)
			(effects
				(font
					(size 1.27 1.27)
					(thickness 0.15)
				)
			)
		)
		(property "Manufacturer" "FTDI Chip"
			(at 383.54 64.77 0)
			(effects
				(font
					(size 1.27 1.27)
					(thickness 0.15)
				)
				(justify left bottom)
				(hide yes)
			)
		)
		(property "License" "Apache-2.0"
			(at 383.54 67.31 0)
			(effects
				(font
					(size 1.27 1.27)
					(thickness 0.15)
				)
				(justify left bottom)
				(hide yes)
			)
		)
		(property "Author" "Antmicro"
			(at 383.54 69.85 0)
			(effects
				(font
					(size 1.27 1.27)
					(thickness 0.15)
				)
				(justify left bottom)
				(hide yes)
			)
		)
		(pin "1"
		)
		(pin "10"
		)
		(pin "11"
		)
		(pin "12"
		)
		(pin "13"
		)
		(pin "14"
		)
		(pin "15"
		)
		(pin "16"
		)
		(pin "17"
		)
		(pin "18"
		)
		(pin "19"
		)
		(pin "2"
		)
		(pin "20"
		)
		(pin "21"
		)
		(pin "22"
		)
		(pin "23"
		)
		(pin "24"
		)
		(pin "25"
		)
		(pin "26"
		)
		(pin "27"
		)
		(pin "28"
		)
		(pin "29"
		)
		(pin "3"
		)
		(pin "30"
		)
		(pin "31"
		)
		(pin "32"
		)
		(pin "33"
		)
		(pin "34"
		)
		(pin "35"
		)
		(pin "36"
		)
		(pin "37"
		)
		(pin "38"
		)
		(pin "39"
		)
		(pin "4"
		)
		(pin "40"
		)
		(pin "41"
		)
		(pin "42"
		)
		(pin "43"
		)
		(pin "44"
		)
		(pin "45"
		)
		(pin "46"
		)
		(pin "47"
		)
		(pin "48"
		)
		(pin "49"
		)
		(pin "5"
		)
		(pin "50"
		)
		(pin "51"
		)
		(pin "52"
		)
		(pin "53"
		)
		(pin "54"
		)
		(pin "55"
		)
		(pin "56"
		)
		(pin "57"
		)
		(pin "58"
		)
		(pin "59"
		)
		(pin "6"
		)
		(pin "60"
		)
		(pin "61"
		)
		(pin "62"
		)
		(pin "63"
		)
		(pin "64"
		)
		(pin "65"
		)
		(pin "66"
		)
		(pin "67"
		)
		(pin "68"
		)
		(pin "69"
		)
		(pin "7"
		)
		(pin "70"
		)
		(pin "71"
		)
		(pin "72"
		)
		(pin "73"
		)
		(pin "74"
		)
		(pin "75"
		)
		(pin "76"
		)
		(pin "77"
		)
		(pin "8"
		)
		(pin "9"
		)
		(instances
			(project "cm4-baseboard"
				(path ""
					(reference "U905")
					(unit 1)
				)
			)
			(project "usb"
				(path ""
					(reference "U905")
					(unit 1)
				)
			)
		)
	)
	(symbol
		(lib_id "antmicroCapacitors0402:C_100n_0402")
		(at 85.09 199.39 270)
		(unit 1)
		(exclude_from_sim no)
		(in_bom yes)
		(on_board yes)
		(dnp no)
		(property "Reference" "C901"
			(at 86.36 199.39 90)
			(effects
				(font
					(size 1.27 1.27)
				)
				(justify left)
			)
		)
		(property "Value" "C_100n_0402"
			(at 81.28 199.39 0)
			(effects
				(font
					(size 1.27 1.27)
					(thickness 0.15)
				)
				(justify left bottom)
				(hide yes)
			)
		)
		(property "Footprint" "antmicro-footprints:C_0402_1005Metric"
			(at 90.17 204.47 0)
			(effects
				(font
					(size 1.27 1.27)
					(thickness 0.15)
				)
				(justify left bottom)
				(hide yes)
			)
		)
		(property "Datasheet" "https://www.murata.com/products/productdetail?partno=GRM155R61H104KE14%23"
			(at 85.09 199.39 0)
			(effects
				(font
					(size 1.27 1.27)
					(thickness 0.15)
				)
				(justify left bottom)
				(hide yes)
			)
		)
		(property "Description" ""
			(at 85.09 199.39 0)
			(effects
				(font
					(size 1.27 1.27)
				)
				(hide yes)
			)
		)
		(property "Manufacturer" "Murata"
			(at 95.25 204.47 0)
			(effects
				(font
					(size 1.27 1.27)
					(thickness 0.15)
				)
				(justify left bottom)
				(hide yes)
			)
		)
		(property "MPN" "GRM155R61H104KE14D"
			(at 92.71 204.47 0)
			(effects
				(font
					(size 1.27 1.27)
					(thickness 0.15)
				)
				(justify left bottom)
				(hide yes)
			)
		)
		(property "Val" "100n"
			(at 86.36 204.47 90)
			(effects
				(font
					(size 1.27 1.27)
					(thickness 0.15)
				)
				(justify left)
			)
		)
		(property "License" "Apache-2.0"
			(at 62.23 219.71 0)
			(effects
				(font
					(size 1.27 1.27)
					(thickness 0.15)
				)
				(justify left bottom)
				(hide yes)
			)
		)
		(property "Author" "Antmicro"
			(at 59.69 219.71 0)
			(effects
				(font
					(size 1.27 1.27)
					(thickness 0.15)
				)
				(justify left bottom)
				(hide yes)
			)
		)
		(property "Voltage" "50V"
			(at 57.15 219.71 0)
			(effects
				(font
					(size 1.27 1.27)
				)
				(justify left bottom)
				(hide yes)
			)
		)
		(property "Dielectric" "X5R"
			(at 54.61 219.71 0)
			(effects
				(font
					(size 1.27 1.27)
				)
				(justify left bottom)
				(hide yes)
			)
		)
		(pin "1"
		)
		(pin "2"
		)
		(instances
			(project "cm4-baseboard"
				(path ""
					(reference "C901")
					(unit 1)
				)
			)
			(project "usb"
				(path ""
					(reference "C901")
					(unit 1)
				)
			)
		)
	)
	(symbol
		(lib_id "antmicroCapacitors0402:C_100n_0402")
		(at 77.47 139.7 270)
		(unit 1)
		(exclude_from_sim no)
		(in_bom yes)
		(on_board yes)
		(dnp no)
		(fields_autoplaced yes)
		(property "Reference" "C909"
			(at 80.01 140.9763 90)
			(effects
				(font
					(size 1.27 1.27)
				)
				(justify left)
			)
		)
		(property "Value" "C_100n_0402"
			(at 73.66 139.7 0)
			(effects
				(font
					(size 1.27 1.27)
					(thickness 0.15)
				)
				(justify left bottom)
				(hide yes)
			)
		)
		(property "Footprint" "antmicro-footprints:C_0402_1005Metric"
			(at 82.55 144.78 0)
			(effects
				(font
					(size 1.27 1.27)
					(thickness 0.15)
				)
				(justify left bottom)
				(hide yes)
			)
		)
		(property "Datasheet" "https://www.murata.com/products/productdetail?partno=GRM155R61H104KE14%23"
			(at 77.47 139.7 0)
			(effects
				(font
					(size 1.27 1.27)
					(thickness 0.15)
				)
				(justify left bottom)
				(hide yes)
			)
		)
		(property "Description" ""
			(at 77.47 139.7 0)
			(effects
				(font
					(size 1.27 1.27)
				)
				(hide yes)
			)
		)
		(property "Manufacturer" "Murata"
			(at 87.63 144.78 0)
			(effects
				(font
					(size 1.27 1.27)
					(thickness 0.15)
				)
				(justify left bottom)
				(hide yes)
			)
		)
		(property "MPN" "GRM155R61H104KE14D"
			(at 85.09 144.78 0)
			(effects
				(font
					(size 1.27 1.27)
					(thickness 0.15)
				)
				(justify left bottom)
				(hide yes)
			)
		)
		(property "Val" "100n"
			(at 80.01 144.1512 90)
			(effects
				(font
					(size 1.27 1.27)
					(thickness 0.15)
				)
				(justify left)
			)
		)
		(property "License" "Apache-2.0"
			(at 54.61 160.02 0)
			(effects
				(font
					(size 1.27 1.27)
					(thickness 0.15)
				)
				(justify left bottom)
				(hide yes)
			)
		)
		(property "Author" "Antmicro"
			(at 52.07 160.02 0)
			(effects
				(font
					(size 1.27 1.27)
					(thickness 0.15)
				)
				(justify left bottom)
				(hide yes)
			)
		)
		(property "Voltage" "50V"
			(at 49.53 160.02 0)
			(effects
				(font
					(size 1.27 1.27)
				)
				(justify left bottom)
				(hide yes)
			)
		)
		(property "Dielectric" "X5R"
			(at 46.99 160.02 0)
			(effects
				(font
					(size 1.27 1.27)
				)
				(justify left bottom)
				(hide yes)
			)
		)
		(pin "1"
		)
		(pin "2"
		)
		(instances
			(project "cm4-baseboard"
				(path ""
					(reference "C909")
					(unit 1)
				)
			)
			(project "usb"
				(path ""
					(reference "C909")
					(unit 1)
				)
			)
		)
	)
	(symbol
		(lib_id "antmicropower:GND")
		(at 66.04 44.45 0)
		(unit 1)
		(exclude_from_sim no)
		(in_bom yes)
		(on_board yes)
		(dnp no)
		(fields_autoplaced yes)
		(property "Reference" "#PWR0904"
			(at 74.93 46.99 0)
			(effects
				(font
					(size 1.27 1.27)
					(thickness 0.15)
				)
				(justify left bottom)
				(hide yes)
			)
		)
		(property "Value" "GND"
			(at 64.0298 49.53 0)
			(effects
				(font
					(size 1.27 1.27)
					(thickness 0.15)
				)
				(justify left bottom)
			)
		)
		(property "Footprint" ""
			(at 74.93 52.07 0)
			(effects
				(font
					(size 1.27 1.27)
					(thickness 0.15)
				)
				(justify left bottom)
				(hide yes)
			)
		)
		(property "Datasheet" ""
			(at 74.93 57.15 0)
			(effects
				(font
					(size 1.27 1.27)
					(thickness 0.15)
				)
				(justify left bottom)
				(hide yes)
			)
		)
		(property "Description" ""
			(at 66.04 44.45 0)
			(effects
				(font
					(size 1.27 1.27)
				)
				(hide yes)
			)
		)
		(property "Author" "Antmicro"
			(at 74.93 52.07 0)
			(effects
				(font
					(size 1.27 1.27)
					(thickness 0.15)
				)
				(justify left bottom)
				(hide yes)
			)
		)
		(property "License" "Apache-2.0"
			(at 74.93 54.61 0)
			(effects
				(font
					(size 1.27 1.27)
					(thickness 0.15)
				)
				(justify left bottom)
				(hide yes)
			)
		)
		(pin "1"
		)
		(instances
			(project "cm4-baseboard"
				(path ""
					(reference "#PWR0904")
					(unit 1)
				)
			)
			(project "usb"
				(path ""
					(reference "#PWR0904")
					(unit 1)
				)
			)
		)
	)
	(symbol
		(lib_id "antmicroTestPoints:TP_0.75mm_SMD")
		(at 77.47 57.15 90)
		(unit 1)
		(exclude_from_sim no)
		(in_bom no)
		(on_board yes)
		(dnp no)
		(property "Reference" "TP920"
			(at 74.93 52.07 90)
			(effects
				(font
					(size 1.27 1.27)
				)
				(justify right)
			)
		)
		(property "Value" "TP_0.75mm_SMD"
			(at 80.01 57.15 0)
			(effects
				(font
					(size 1.27 1.27)
					(thickness 0.15)
				)
				(justify left bottom)
				(hide yes)
			)
		)
		(property "Footprint" "antmicro-footprints:TP_SMD_0.75mm"
			(at 72.39 52.07 0)
			(effects
				(font
					(size 1.27 1.27)
					(thickness 0.15)
				)
				(justify left bottom)
				(hide yes)
			)
		)
		(property "Datasheet" ""
			(at 69.85 52.07 0)
			(effects
				(font
					(size 1.27 1.27)
					(thickness 0.15)
				)
				(justify left bottom)
				(hide yes)
			)
		)
		(property "Description" ""
			(at 77.47 57.15 0)
			(effects
				(font
					(size 1.27 1.27)
				)
				(hide yes)
			)
		)
		(property "MPN" ""
			(at 77.47 57.15 0)
			(effects
				(font
					(size 1.27 1.27)
					(thickness 0.15)
				)
				(justify left bottom)
				(hide yes)
			)
		)
		(property "Manufacturer" ""
			(at 77.47 57.15 0)
			(effects
				(font
					(size 1.27 1.27)
					(thickness 0.15)
				)
				(justify left bottom)
				(hide yes)
			)
		)
		(property "Author" "Antmicro"
			(at 92.71 41.91 0)
			(effects
				(font
					(size 1.27 1.27)
					(thickness 0.15)
				)
				(justify left bottom)
				(hide yes)
			)
		)
		(property "License" "Apache-2.0"
			(at 95.25 41.91 0)
			(effects
				(font
					(size 1.27 1.27)
					(thickness 0.15)
				)
				(justify left bottom)
				(hide yes)
			)
		)
		(pin "1"
		)
		(instances
			(project "cm4-baseboard"
				(path ""
					(reference "TP920")
					(unit 1)
				)
			)
		)
	)
	(symbol
		(lib_id "antmicroResistors0402:R_4k7_0402")
		(at 220.98 201.93 270)
		(mirror x)
		(unit 1)
		(exclude_from_sim no)
		(in_bom yes)
		(on_board yes)
		(dnp no)
		(property "Reference" "R927"
			(at 219.71 198.12 90)
			(effects
				(font
					(size 1.27 1.27)
				)
				(justify right)
			)
		)
		(property "Value" "R_4k7_0402"
			(at 217.17 201.93 0)
			(effects
				(font
					(size 1.27 1.27)
				)
				(justify left bottom)
				(hide yes)
			)
		)
		(property "Footprint" "antmicro-footprints:R_0402_1005Metric"
			(at 226.06 196.85 0)
			(effects
				(font
					(size 1.524 1.524)
				)
				(justify left bottom)
				(hide yes)
			)
		)
		(property "Datasheet" "https://www.bourns.com/docs/product-datasheets/cr.pdf"
			(at 220.98 201.93 0)
			(effects
				(font
					(size 1.27 1.27)
				)
				(justify left bottom)
				(hide yes)
			)
		)
		(property "Description" ""
			(at 220.98 201.93 0)
			(effects
				(font
					(size 1.27 1.27)
				)
				(hide yes)
			)
		)
		(property "Manufacturer" "Bourns"
			(at 231.14 196.85 0)
			(effects
				(font
					(size 1.524 1.524)
				)
				(justify left bottom)
				(hide yes)
			)
		)
		(property "MPN" "CR0402-FX-4701GLF"
			(at 228.6 196.85 0)
			(effects
				(font
					(size 1.524 1.524)
				)
				(justify left bottom)
				(hide yes)
			)
		)
		(property "Val" "4k7"
			(at 219.71 200.66 90)
			(effects
				(font
					(size 1.27 1.27)
				)
				(justify right)
			)
		)
		(property "License" "Apache-2.0"
			(at 195.58 181.61 0)
			(effects
				(font
					(size 1.27 1.27)
					(thickness 0.15)
				)
				(justify left bottom)
				(hide yes)
			)
		)
		(property "Author" "Antmicro"
			(at 193.04 181.61 0)
			(effects
				(font
					(size 1.27 1.27)
					(thickness 0.15)
				)
				(justify left bottom)
				(hide yes)
			)
		)
		(property "Tolerance" "1%"
			(at 210.82 181.61 0)
			(effects
				(font
					(size 1.27 1.27)
				)
				(justify left bottom)
				(hide yes)
			)
		)
		(pin "1"
		)
		(pin "2"
		)
		(instances
			(project "cm4-baseboard"
				(path ""
					(reference "R927")
					(unit 1)
				)
			)
			(project "usb"
				(path ""
					(reference "R927")
					(unit 1)
				)
			)
		)
	)
	(symbol
		(lib_id "antmicroTestPoints:TP_0.75mm_SMD")
		(at 161.29 257.81 0)
		(mirror x)
		(unit 1)
		(exclude_from_sim no)
		(in_bom no)
		(on_board yes)
		(dnp no)
		(property "Reference" "TP909"
			(at 165.1 257.81 0)
			(effects
				(font
					(size 1.27 1.27)
				)
				(justify left)
			)
		)
		(property "Value" "TP_0.75mm_SMD"
			(at 161.29 255.27 0)
			(effects
				(font
					(size 1.27 1.27)
					(thickness 0.15)
				)
				(justify left bottom)
				(hide yes)
			)
		)
		(property "Footprint" "antmicro-footprints:TP_SMD_0.75mm"
			(at 166.37 262.89 0)
			(effects
				(font
					(size 1.27 1.27)
					(thickness 0.15)
				)
				(justify left bottom)
				(hide yes)
			)
		)
		(property "Datasheet" ""
			(at 166.37 265.43 0)
			(effects
				(font
					(size 1.27 1.27)
					(thickness 0.15)
				)
				(justify left bottom)
				(hide yes)
			)
		)
		(property "Description" ""
			(at 161.29 257.81 0)
			(effects
				(font
					(size 1.27 1.27)
				)
				(hide yes)
			)
		)
		(property "MPN" ""
			(at 161.29 257.81 0)
			(effects
				(font
					(size 1.27 1.27)
					(thickness 0.15)
				)
				(justify left bottom)
				(hide yes)
			)
		)
		(property "Manufacturer" ""
			(at 161.29 257.81 0)
			(effects
				(font
					(size 1.27 1.27)
					(thickness 0.15)
				)
				(justify left bottom)
				(hide yes)
			)
		)
		(property "Author" "Antmicro"
			(at 176.53 242.57 0)
			(effects
				(font
					(size 1.27 1.27)
					(thickness 0.15)
				)
				(justify left bottom)
				(hide yes)
			)
		)
		(property "License" "Apache-2.0"
			(at 176.53 240.03 0)
			(effects
				(font
					(size 1.27 1.27)
					(thickness 0.15)
				)
				(justify left bottom)
				(hide yes)
			)
		)
		(pin "1"
		)
		(instances
			(project "cm4-baseboard"
				(path ""
					(reference "TP909")
					(unit 1)
				)
			)
			(project "usb"
				(path ""
					(reference "TP909")
					(unit 1)
				)
			)
		)
	)
	(symbol
		(lib_id "antmicropower:GND")
		(at 270.51 156.21 0)
		(unit 1)
		(exclude_from_sim no)
		(in_bom yes)
		(on_board yes)
		(dnp no)
		(fields_autoplaced yes)
		(property "Reference" "#PWR0937"
			(at 270.51 162.56 0)
			(effects
				(font
					(size 1.27 1.27)
				)
				(hide yes)
			)
		)
		(property "Value" "GND"
			(at 270.51 161.29 0)
			(effects
				(font
					(size 1.27 1.27)
				)
			)
		)
		(property "Footprint" ""
			(at 279.4 163.83 0)
			(effects
				(font
					(size 1.27 1.27)
					(thickness 0.15)
				)
				(justify left bottom)
				(hide yes)
			)
		)
		(property "Datasheet" ""
			(at 279.4 168.91 0)
			(effects
				(font
					(size 1.27 1.27)
					(thickness 0.15)
				)
				(justify left bottom)
				(hide yes)
			)
		)
		(property "Description" ""
			(at 270.51 156.21 0)
			(effects
				(font
					(size 1.27 1.27)
				)
				(hide yes)
			)
		)
		(property "Author" "Antmicro"
			(at 279.4 163.83 0)
			(effects
				(font
					(size 1.27 1.27)
					(thickness 0.15)
				)
				(justify left bottom)
				(hide yes)
			)
		)
		(property "License" "Apache-2.0"
			(at 279.4 166.37 0)
			(effects
				(font
					(size 1.27 1.27)
					(thickness 0.15)
				)
				(justify left bottom)
				(hide yes)
			)
		)
		(pin "1"
		)
		(instances
			(project "cm4-baseboard"
				(path ""
					(reference "#PWR0937")
					(unit 1)
				)
			)
			(project "usb"
				(path ""
					(reference "#PWR0937")
					(unit 1)
				)
			)
		)
	)
	(symbol
		(lib_id "antmicroResistors0402:R_10k_0402")
		(at 243.84 191.77 270)
		(mirror x)
		(unit 1)
		(exclude_from_sim no)
		(in_bom yes)
		(on_board yes)
		(dnp no)
		(property "Reference" "R928"
			(at 245.11 187.96 90)
			(effects
				(font
					(size 1.27 1.27)
				)
				(justify left)
			)
		)
		(property "Value" "R_10k_0402"
			(at 231.14 171.45 0)
			(effects
				(font
					(size 1.27 1.27)
					(thickness 0.15)
				)
				(justify left bottom)
				(hide yes)
			)
		)
		(property "Footprint" "antmicro-footprints:R_0402_1005Metric"
			(at 228.6 171.45 0)
			(effects
				(font
					(size 1.27 1.27)
					(thickness 0.15)
				)
				(justify left bottom)
				(hide yes)
			)
		)
		(property "Datasheet" "https://www.bourns.com/docs/product-datasheets/cr.pdf"
			(at 226.06 171.45 0)
			(effects
				(font
					(size 1.27 1.27)
					(thickness 0.15)
				)
				(justify left bottom)
				(hide yes)
			)
		)
		(property "Description" ""
			(at 243.84 191.77 0)
			(effects
				(font
					(size 1.27 1.27)
				)
				(hide yes)
			)
		)
		(property "Manufacturer" "Bourns"
			(at 220.98 171.45 0)
			(effects
				(font
					(size 1.27 1.27)
					(thickness 0.15)
				)
				(justify left bottom)
				(hide yes)
			)
		)
		(property "MPN" "CR0402-FX-1002GLF"
			(at 223.52 171.45 0)
			(effects
				(font
					(size 1.27 1.27)
					(thickness 0.15)
				)
				(justify left bottom)
				(hide yes)
			)
		)
		(property "Val" "10k"
			(at 245.11 190.5 90)
			(effects
				(font
					(size 1.27 1.27)
					(thickness 0.15)
				)
				(justify left)
			)
		)
		(property "License" "Apache-2.0"
			(at 218.44 171.45 0)
			(effects
				(font
					(size 1.27 1.27)
					(thickness 0.15)
				)
				(justify left bottom)
				(hide yes)
			)
		)
		(property "Author" "Antmicro"
			(at 215.9 171.45 0)
			(effects
				(font
					(size 1.27 1.27)
					(thickness 0.15)
				)
				(justify left bottom)
				(hide yes)
			)
		)
		(property "Tolerance" "1%"
			(at 233.68 171.45 0)
			(effects
				(font
					(size 1.27 1.27)
				)
				(justify left bottom)
				(hide yes)
			)
		)
		(pin "1"
		)
		(pin "2"
		)
		(instances
			(project "cm4-baseboard"
				(path ""
					(reference "R928")
					(unit 1)
				)
			)
			(project "usb"
				(path ""
					(reference "R928")
					(unit 1)
				)
			)
		)
	)
	(symbol
		(lib_id "antmicroDCDCConverters:AP62301_TSOT")
		(at 180.34 54.61 0)
		(unit 1)
		(exclude_from_sim no)
		(in_bom yes)
		(on_board yes)
		(dnp no)
		(fields_autoplaced yes)
		(property "Reference" "U903"
			(at 190.5 46.99 0)
			(effects
				(font
					(size 1.27 1.27)
					(thickness 0.15)
				)
			)
		)
		(property "Value" "AP62301_TSOT"
			(at 215.9 62.23 0)
			(effects
				(font
					(size 1.27 1.27)
					(thickness 0.15)
				)
				(justify left bottom)
				(hide yes)
			)
		)
		(property "Footprint" "antmicro-footprints:TSOT23-6"
			(at 215.9 64.77 0)
			(effects
				(font
					(size 1.27 1.27)
					(thickness 0.15)
				)
				(justify left bottom)
				(hide yes)
			)
		)
		(property "Datasheet" "https://www.diodes.com/assets/Datasheets/AP62300_AP62301_AP62300T.pdf"
			(at 215.9 67.31 0)
			(effects
				(font
					(size 1.27 1.27)
					(thickness 0.15)
				)
				(justify left bottom)
				(hide yes)
			)
		)
		(property "Description" ""
			(at 180.34 54.61 0)
			(effects
				(font
					(size 1.27 1.27)
				)
				(hide yes)
			)
		)
		(property "MPN" "AP62301WU-7"
			(at 190.5 49.53 0)
			(effects
				(font
					(size 1.27 1.27)
					(thickness 0.15)
				)
			)
		)
		(property "Manufacturer" "Diodes Incorporated"
			(at 215.9 69.85 0)
			(effects
				(font
					(size 1.27 1.27)
					(thickness 0.15)
				)
				(justify left bottom)
				(hide yes)
			)
		)
		(property "Author" "Antmicro"
			(at 215.9 72.39 0)
			(effects
				(font
					(size 1.27 1.27)
					(thickness 0.15)
				)
				(justify left bottom)
				(hide yes)
			)
		)
		(property "License" "Apache-2.0"
			(at 215.9 74.93 0)
			(effects
				(font
					(size 1.27 1.27)
					(thickness 0.15)
				)
				(justify left bottom)
				(hide yes)
			)
		)
		(pin "1"
		)
		(pin "2"
		)
		(pin "3"
		)
		(pin "4"
		)
		(pin "5"
		)
		(pin "6"
		)
		(instances
			(project "cm4-baseboard"
				(path ""
					(reference "U903")
					(unit 1)
				)
			)
			(project "usb"
				(path ""
					(reference "U903")
					(unit 1)
				)
			)
		)
	)
	(symbol
		(lib_id "antmicropower:GND")
		(at 77.47 66.04 0)
		(unit 1)
		(exclude_from_sim no)
		(in_bom yes)
		(on_board yes)
		(dnp no)
		(fields_autoplaced yes)
		(property "Reference" "#PWR0908"
			(at 86.36 68.58 0)
			(effects
				(font
					(size 1.27 1.27)
					(thickness 0.15)
				)
				(justify left bottom)
				(hide yes)
			)
		)
		(property "Value" "GND"
			(at 75.4598 71.12 0)
			(effects
				(font
					(size 1.27 1.27)
					(thickness 0.15)
				)
				(justify left bottom)
			)
		)
		(property "Footprint" ""
			(at 86.36 73.66 0)
			(effects
				(font
					(size 1.27 1.27)
					(thickness 0.15)
				)
				(justify left bottom)
				(hide yes)
			)
		)
		(property "Datasheet" ""
			(at 86.36 78.74 0)
			(effects
				(font
					(size 1.27 1.27)
					(thickness 0.15)
				)
				(justify left bottom)
				(hide yes)
			)
		)
		(property "Description" ""
			(at 77.47 66.04 0)
			(effects
				(font
					(size 1.27 1.27)
				)
				(hide yes)
			)
		)
		(property "Author" "Antmicro"
			(at 86.36 73.66 0)
			(effects
				(font
					(size 1.27 1.27)
					(thickness 0.15)
				)
				(justify left bottom)
				(hide yes)
			)
		)
		(property "License" "Apache-2.0"
			(at 86.36 76.2 0)
			(effects
				(font
					(size 1.27 1.27)
					(thickness 0.15)
				)
				(justify left bottom)
				(hide yes)
			)
		)
		(pin "1"
		)
		(instances
			(project "cm4-baseboard"
				(path ""
					(reference "#PWR0908")
					(unit 1)
				)
			)
			(project "usb"
				(path ""
					(reference "#PWR0908")
					(unit 1)
				)
			)
		)
	)
	(symbol
		(lib_id "antmicropower:+5V")
		(at 102.87 66.04 0)
		(unit 1)
		(exclude_from_sim no)
		(in_bom yes)
		(on_board yes)
		(dnp no)
		(fields_autoplaced yes)
		(property "Reference" "#PWR028"
			(at 118.11 68.58 0)
			(effects
				(font
					(size 1.27 1.27)
					(thickness 0.15)
				)
				(justify left bottom)
				(hide yes)
			)
		)
		(property "Value" "+5V"
			(at 102.87 62.23 0)
			(effects
				(font
					(size 1.27 1.27)
					(thickness 0.15)
				)
			)
		)
		(property "Footprint" ""
			(at 118.11 73.66 0)
			(effects
				(font
					(size 1.27 1.27)
					(thickness 0.15)
				)
				(justify left bottom)
				(hide yes)
			)
		)
		(property "Datasheet" ""
			(at 118.11 76.2 0)
			(effects
				(font
					(size 1.27 1.27)
					(thickness 0.15)
				)
				(justify left bottom)
				(hide yes)
			)
		)
		(property "Description" ""
			(at 102.87 66.04 0)
			(effects
				(font
					(size 1.27 1.27)
				)
				(hide yes)
			)
		)
		(property "Author" "Antmicro"
			(at 118.11 73.66 0)
			(effects
				(font
					(size 1.27 1.27)
					(thickness 0.15)
				)
				(justify left bottom)
				(hide yes)
			)
		)
		(property "License" "Apache-2.0"
			(at 118.11 76.2 0)
			(effects
				(font
					(size 1.27 1.27)
					(thickness 0.15)
				)
				(justify left bottom)
				(hide yes)
			)
		)
		(pin "1"
		)
		(instances
			(project "cm4-baseboard"
				(path ""
					(reference "#PWR028")
					(unit 1)
				)
			)
		)
	)
	(symbol
		(lib_id "antmicropower:GND")
		(at 299.72 77.47 0)
		(unit 1)
		(exclude_from_sim no)
		(in_bom yes)
		(on_board yes)
		(dnp no)
		(property "Reference" "#PWR0916"
			(at 299.72 83.82 0)
			(effects
				(font
					(size 1.27 1.27)
				)
				(hide yes)
			)
		)
		(property "Value" "GND"
			(at 299.72 81.28 0)
			(effects
				(font
					(size 1.27 1.27)
				)
			)
		)
		(property "Footprint" ""
			(at 308.61 85.09 0)
			(effects
				(font
					(size 1.27 1.27)
					(thickness 0.15)
				)
				(justify left bottom)
				(hide yes)
			)
		)
		(property "Datasheet" ""
			(at 308.61 90.17 0)
			(effects
				(font
					(size 1.27 1.27)
					(thickness 0.15)
				)
				(justify left bottom)
				(hide yes)
			)
		)
		(property "Description" ""
			(at 299.72 77.47 0)
			(effects
				(font
					(size 1.27 1.27)
				)
				(hide yes)
			)
		)
		(property "Author" "Antmicro"
			(at 308.61 85.09 0)
			(effects
				(font
					(size 1.27 1.27)
					(thickness 0.15)
				)
				(justify left bottom)
				(hide yes)
			)
		)
		(property "License" "Apache-2.0"
			(at 308.61 87.63 0)
			(effects
				(font
					(size 1.27 1.27)
					(thickness 0.15)
				)
				(justify left bottom)
				(hide yes)
			)
		)
		(pin "1"
		)
		(instances
			(project "cm4-baseboard"
				(path ""
					(reference "#PWR0916")
					(unit 1)
				)
			)
			(project "usb"
				(path ""
					(reference "#PWR0916")
					(unit 1)
				)
			)
		)
	)
	(symbol
		(lib_id "antmicropower:GND")
		(at 220.98 203.2 0)
		(mirror y)
		(unit 1)
		(exclude_from_sim no)
		(in_bom yes)
		(on_board yes)
		(dnp no)
		(fields_autoplaced yes)
		(property "Reference" "#PWR08"
			(at 220.98 209.55 0)
			(effects
				(font
					(size 1.27 1.27)
				)
				(justify left bottom)
				(hide yes)
			)
		)
		(property "Value" "GND"
			(at 220.98 208.28 0)
			(effects
				(font
					(size 1.27 1.27)
				)
			)
		)
		(property "Footprint" ""
			(at 212.09 210.82 0)
			(effects
				(font
					(size 1.27 1.27)
					(thickness 0.15)
				)
				(justify left bottom)
				(hide yes)
			)
		)
		(property "Datasheet" ""
			(at 212.09 215.9 0)
			(effects
				(font
					(size 1.27 1.27)
					(thickness 0.15)
				)
				(justify left bottom)
				(hide yes)
			)
		)
		(property "Description" ""
			(at 220.98 203.2 0)
			(effects
				(font
					(size 1.27 1.27)
				)
				(hide yes)
			)
		)
		(property "Author" "Antmicro"
			(at 212.09 210.82 0)
			(effects
				(font
					(size 1.27 1.27)
					(thickness 0.15)
				)
				(justify left bottom)
				(hide yes)
			)
		)
		(property "License" "Apache-2.0"
			(at 212.09 213.36 0)
			(effects
				(font
					(size 1.27 1.27)
					(thickness 0.15)
				)
				(justify left bottom)
				(hide yes)
			)
		)
		(pin "1"
		)
		(instances
			(project "cm4-baseboard"
				(path ""
					(reference "#PWR08")
					(unit 1)
				)
			)
			(project "usb"
				(path ""
					(reference "#PWR08")
					(unit 1)
				)
			)
		)
	)
	(symbol
		(lib_id "antmicroResistors0402:R_10k_0402")
		(at 198.12 125.73 270)
		(unit 1)
		(exclude_from_sim no)
		(in_bom no)
		(on_board yes)
		(dnp yes)
		(property "Reference" "R911"
			(at 199.39 127.635 90)
			(effects
				(font
					(size 1.27 1.27)
				)
				(justify left)
			)
		)
		(property "Value" "R_10k_0402"
			(at 194.31 125.73 0)
			(effects
				(font
					(size 1.27 1.27)
					(thickness 0.15)
				)
				(justify left bottom)
				(hide yes)
			)
		)
		(property "Footprint" "antmicro-footprints:R_0402_1005Metric"
			(at 203.2 130.81 0)
			(effects
				(font
					(size 1.27 1.27)
					(thickness 0.15)
				)
				(justify left bottom)
				(hide yes)
			)
		)
		(property "Datasheet" "https://www.bourns.com/docs/product-datasheets/cr.pdf"
			(at 198.12 125.73 0)
			(effects
				(font
					(size 1.27 1.27)
					(thickness 0.15)
				)
				(justify left bottom)
				(hide yes)
			)
		)
		(property "Description" ""
			(at 198.12 125.73 0)
			(effects
				(font
					(size 1.27 1.27)
				)
				(hide yes)
			)
		)
		(property "Manufacturer" "Bourns"
			(at 208.28 130.81 0)
			(effects
				(font
					(size 1.27 1.27)
					(thickness 0.15)
				)
				(justify left bottom)
				(hide yes)
			)
		)
		(property "MPN" "CR0402-FX-1002GLF"
			(at 205.74 130.81 0)
			(effects
				(font
					(size 1.27 1.27)
					(thickness 0.15)
				)
				(justify left bottom)
				(hide yes)
			)
		)
		(property "Val" "10k"
			(at 199.39 129.5399 90)
			(effects
				(font
					(size 1.27 1.27)
					(thickness 0.15)
				)
				(justify left)
			)
		)
		(property "License" "Apache-2.0"
			(at 172.72 146.05 0)
			(effects
				(font
					(size 1.27 1.27)
					(thickness 0.15)
				)
				(justify left bottom)
				(hide yes)
			)
		)
		(property "Author" "Antmicro"
			(at 170.18 146.05 0)
			(effects
				(font
					(size 1.27 1.27)
					(thickness 0.15)
				)
				(justify left bottom)
				(hide yes)
			)
		)
		(property "Tolerance" "1%"
			(at 187.96 146.05 0)
			(effects
				(font
					(size 1.27 1.27)
				)
				(justify left bottom)
				(hide yes)
			)
		)
		(pin "1"
		)
		(pin "2"
		)
		(instances
			(project "cm4-baseboard"
				(path ""
					(reference "R911")
					(unit 1)
				)
			)
			(project "usb"
				(path ""
					(reference "R911")
					(unit 1)
				)
			)
		)
	)
	(symbol
		(lib_id "antmicroResistors0402:R_100k_0402")
		(at 111.76 59.69 270)
		(unit 1)
		(exclude_from_sim no)
		(in_bom yes)
		(on_board yes)
		(dnp no)
		(property "Reference" "R904"
			(at 113.03 60.96 90)
			(effects
				(font
					(size 1.27 1.27)
				)
				(justify left)
			)
		)
		(property "Value" "R_100k_0402"
			(at 107.95 59.69 0)
			(effects
				(font
					(size 1.27 1.27)
					(thickness 0.15)
				)
				(justify left bottom)
				(hide yes)
			)
		)
		(property "Footprint" "antmicro-footprints:R_0402_1005Metric"
			(at 116.84 64.77 0)
			(effects
				(font
					(size 1.27 1.27)
					(thickness 0.15)
				)
				(justify left bottom)
				(hide yes)
			)
		)
		(property "Datasheet" "https://www.bourns.com/docs/product-datasheets/cr.pdf"
			(at 111.76 59.69 0)
			(effects
				(font
					(size 1.27 1.27)
					(thickness 0.15)
				)
				(justify left bottom)
				(hide yes)
			)
		)
		(property "Description" ""
			(at 111.76 59.69 0)
			(effects
				(font
					(size 1.27 1.27)
				)
				(hide yes)
			)
		)
		(property "Manufacturer" "Bourns"
			(at 121.92 64.77 0)
			(effects
				(font
					(size 1.27 1.27)
					(thickness 0.15)
				)
				(justify left bottom)
				(hide yes)
			)
		)
		(property "MPN" "CR0402-FX-1003GLF"
			(at 119.38 64.77 0)
			(effects
				(font
					(size 1.27 1.27)
					(thickness 0.15)
				)
				(justify left bottom)
				(hide yes)
			)
		)
		(property "Val" "100k"
			(at 113.03 64.1349 90)
			(effects
				(font
					(size 1.27 1.27)
					(thickness 0.15)
				)
				(justify left)
			)
		)
		(property "License" "Apache-2.0"
			(at 86.36 80.01 0)
			(effects
				(font
					(size 1.27 1.27)
					(thickness 0.15)
				)
				(justify left bottom)
				(hide yes)
			)
		)
		(property "Author" "Antmicro"
			(at 83.82 80.01 0)
			(effects
				(font
					(size 1.27 1.27)
					(thickness 0.15)
				)
				(justify left bottom)
				(hide yes)
			)
		)
		(property "Tolerance" "1%"
			(at 101.6 80.01 0)
			(effects
				(font
					(size 1.27 1.27)
				)
				(justify left bottom)
				(hide yes)
			)
		)
		(pin "1"
		)
		(pin "2"
		)
		(instances
			(project "cm4-baseboard"
				(path ""
					(reference "R904")
					(unit 1)
				)
			)
			(project "usb"
				(path ""
					(reference "R904")
					(unit 1)
				)
			)
		)
	)
	(symbol
		(lib_id "antmicroLEDIndicationDiscrete:LED_Y_0402_VLMY1500-GS08")
		(at 317.5 116.84 270)
		(mirror x)
		(unit 1)
		(exclude_from_sim no)
		(in_bom yes)
		(on_board yes)
		(dnp no)
		(property "Reference" "D911"
			(at 314.96 113.03 90)
			(effects
				(font
					(size 1.27 1.27)
					(thickness 0.15)
				)
				(justify right)
			)
		)
		(property "Value" "LED_Y_0402_VLMY1500-GS08"
			(at 307.34 93.98 0)
			(effects
				(font
					(size 1.27 1.27)
					(thickness 0.15)
				)
				(justify left bottom)
				(hide yes)
			)
		)
		(property "Footprint" "antmicro-footprints:LED_0402_1005Metric_Y"
			(at 304.8 93.98 0)
			(effects
				(font
					(size 1.27 1.27)
					(thickness 0.15)
				)
				(justify left bottom)
				(hide yes)
			)
		)
		(property "Datasheet" "https://www.vishay.com/docs/82554/vlmo1500.pdf"
			(at 302.26 93.98 0)
			(effects
				(font
					(size 1.27 1.27)
					(thickness 0.15)
				)
				(justify left bottom)
				(hide yes)
			)
		)
		(property "Description" ""
			(at 317.5 116.84 0)
			(effects
				(font
					(size 1.27 1.27)
				)
				(hide yes)
			)
		)
		(property "MPN" "VLMY1500-GS08"
			(at 309.88 93.98 0)
			(effects
				(font
					(size 1.27 1.27)
					(thickness 0.15)
				)
				(justify left bottom)
				(hide yes)
			)
		)
		(property "Manufacturer" "Vishay"
			(at 299.72 93.98 0)
			(effects
				(font
					(size 1.27 1.27)
					(thickness 0.15)
				)
				(justify left bottom)
				(hide yes)
			)
		)
		(property "Author" "Antmicro"
			(at 294.64 93.98 0)
			(effects
				(font
					(size 1.27 1.27)
					(thickness 0.15)
				)
				(justify left bottom)
				(hide yes)
			)
		)
		(property "License" "Apache-2.0"
			(at 292.1 93.98 0)
			(effects
				(font
					(size 1.27 1.27)
					(thickness 0.15)
				)
				(justify left bottom)
				(hide yes)
			)
		)
		(property "Color" "Yellow"
			(at 314.96 115.57 90)
			(effects
				(font
					(size 1.27 1.27)
				)
				(justify right)
			)
		)
		(pin "1"
		)
		(pin "2"
		)
		(instances
			(project "cm4-baseboard"
				(path ""
					(reference "D911")
					(unit 1)
				)
			)
			(project "usb"
				(path ""
					(reference "D911")
					(unit 1)
				)
			)
		)
	)
	(symbol
		(lib_id "antmicroResistors0402:R_12k_0402")
		(at 331.47 154.94 90)
		(unit 1)
		(exclude_from_sim no)
		(in_bom yes)
		(on_board yes)
		(dnp no)
		(property "Reference" "R922"
			(at 329.565 151.13 90)
			(effects
				(font
					(size 1.27 1.27)
				)
				(justify left)
			)
		)
		(property "Value" "R_12k_0402"
			(at 335.28 154.94 0)
			(effects
				(font
					(size 1.27 1.27)
					(thickness 0.15)
				)
				(justify left bottom)
				(hide yes)
			)
		)
		(property "Footprint" "antmicro-footprints:R_0402_1005Metric"
			(at 326.39 149.86 0)
			(effects
				(font
					(size 1.27 1.27)
					(thickness 0.15)
				)
				(justify left bottom)
				(hide yes)
			)
		)
		(property "Datasheet" "https://www.bourns.com/docs/product-datasheets/cr.pdf"
			(at 331.47 154.94 0)
			(effects
				(font
					(size 1.27 1.27)
					(thickness 0.15)
				)
				(justify left bottom)
				(hide yes)
			)
		)
		(property "Description" ""
			(at 331.47 154.94 0)
			(effects
				(font
					(size 1.27 1.27)
				)
				(hide yes)
			)
		)
		(property "Manufacturer" "Bourns"
			(at 321.31 149.86 0)
			(effects
				(font
					(size 1.27 1.27)
					(thickness 0.15)
				)
				(justify left bottom)
				(hide yes)
			)
		)
		(property "MPN" "CR0402-FX-1202GLF"
			(at 323.85 149.86 0)
			(effects
				(font
					(size 1.27 1.27)
					(thickness 0.15)
				)
				(justify left bottom)
				(hide yes)
			)
		)
		(property "Val" "12k"
			(at 329.565 153.67 90)
			(effects
				(font
					(size 1.27 1.27)
					(thickness 0.15)
				)
				(justify left)
			)
		)
		(property "License" "Apache-2.0"
			(at 356.87 134.62 0)
			(effects
				(font
					(size 1.27 1.27)
					(thickness 0.15)
				)
				(justify left bottom)
				(hide yes)
			)
		)
		(property "Author" "Antmicro"
			(at 359.41 134.62 0)
			(effects
				(font
					(size 1.27 1.27)
					(thickness 0.15)
				)
				(justify left bottom)
				(hide yes)
			)
		)
		(property "Tolerance" "1%"
			(at 341.63 134.62 0)
			(effects
				(font
					(size 1.27 1.27)
				)
				(justify left bottom)
				(hide yes)
			)
		)
		(pin "1"
		)
		(pin "2"
		)
		(instances
			(project "cm4-baseboard"
				(path ""
					(reference "R922")
					(unit 1)
				)
			)
			(project "usb"
				(path ""
					(reference "R922")
					(unit 1)
				)
			)
		)
	)
	(sheet_instances
		(path "/"
			(page "1")
		)
	)
)
